FILE_TYPE = MACRO_DRAWING;
SET COLOR_WIRE YELLOW;
SET COLOR_PROP MONO;
SET COLOR_DOT WHITE;
SET COLOR_ARC YELLOW;
SET COLOR_BODY GREEN;
SET COLOR_NOTE MONO;
SET PROP_DISPLAY VALUE;
SET PAGE_NUMBER P86;
FORCEADD GND..1
R 2
(-3525 1525);
FORCEPROP 3 LASTPIN (-3525 1575) SIG_NAME GND\g
J 0
(-3515 1585);
DISPLAY 0.659574 (-3515 1585);
PAINT MONO (-3515 1585);
DISPLAY INVISIBLE (-3515 1585);
FORCEPROP 1 LAST VOLTAGE 0
J 0
(-3525 1525);
PAINT SKYBLUE (-3525 1525);
DISPLAY INVISIBLE (-3525 1525);
FORCEPROP 2 LAST CDS_LIB mstr_symbols
J 0
(-3525 1525);
DISPLAY 0.787234 (-3525 1525);
PAINT MONO (-3525 1525);
DISPLAY INVISIBLE (-3525 1525);
FORCEPROP 1 LAST SIZE 1B
J 2
(-3600 1475);
DISPLAY 1.170213 (-3600 1475);
PAINT GREEN (-3600 1475);
DISPLAY INVISIBLE (-3600 1475);
FORCEPROP 2 LAST BOM_COST MEM
J 0
(-3525 1530);
PAINT ORANGE (-3525 1530);
DISPLAY INVISIBLE (-3525 1530);
FORCEPROP 1 LAST BODY_TYPE PLUMBING
J 2
(-3480 1482);
DISPLAY 0.340426 (-3480 1482);
PAINT GREEN (-3480 1482);
DISPLAY INVISIBLE (-3480 1482);
FORCEPROP 1 LAST PATH I1
J 2
(-3600 1525);
DISPLAY 0.872340 (-3600 1525);
PAINT AQUA (-3600 1525);
DISPLAY INVISIBLE (-3600 1525);
FORCEPROP 2 LAST ROOM DDR4_CH_D
J 0
(-3525 1530);
PAINT ORANGE (-3525 1530);
DISPLAY INVISIBLE (-3525 1530);
FORCEPROP 1 LAST HDL_POWER GND
J 2
(-3525 1675);
DISPLAY 0.553191 (-3525 1675);
PAINT GREEN (-3525 1675);
DISPLAY INVISIBLE (-3525 1675);
FORCEADD OFFPAGE..1
(-2225 1525);
FORCEPROP 2 LAST $XR0 99 
J 0
(-2476 1525);
DISPLAY 0.638298 (-2476 1525);
PAINT MONO (-2476 1525);
FORCEPROP 2 LAST $XR1 83 
J 0
(-2566 1525);
DISPLAY 0.638298 (-2566 1525);
PAINT MONO (-2566 1525);
FORCEPROP 2 LAST $XR2 84 
J 0
(-2656 1525);
DISPLAY 0.638298 (-2656 1525);
PAINT MONO (-2656 1525);
FORCEPROP 2 LAST $XR3 85 
J 0
(-2746 1525);
DISPLAY 0.638298 (-2746 1525);
PAINT MONO (-2746 1525);
FORCEPROP 2 LAST $XR4 87 
J 0
(-2836 1525);
DISPLAY 0.638298 (-2836 1525);
PAINT MONO (-2836 1525);
FORCEPROP 2 LAST $XR5 88 
J 0
(-2926 1525);
DISPLAY 0.638298 (-2926 1525);
PAINT MONO (-2926 1525);
FORCEPROP 2 LAST CDS_LIB mstr_standard
J 0
(-2225 1525);
DISPLAY 0.787234 (-2225 1525);
PAINT MONO (-2225 1525);
DISPLAY INVISIBLE (-2225 1525);
FORCEPROP 1 LAST OFFPAGE TRUE
J 0
(-1900 1400);
DISPLAY 0.936170 (-1900 1400);
PAINT GREEN (-1900 1400);
DISPLAY INVISIBLE (-1900 1400);
FORCEPROP 1 LAST COMMENT_BODY TRUE
J 0
(-2100 1425);
DISPLAY 0.936170 (-2100 1425);
PAINT GREEN (-2100 1425);
DISPLAY INVISIBLE (-2100 1425);
FORCEPROP 2 LAST PATH I10
J 0
(-2475 1575);
DISPLAY 1.021277 (-2475 1575);
PAINT ORANGE (-2475 1575);
DISPLAY INVISIBLE (-2475 1575);
FORCEADD SCONN288_H44441003..2
(1625 3975);
FORCEPROP 1 LAST LOCATION J9L2
J 0
(1225 5075);
DISPLAY 0.617021 (1225 5075);
PAINT AQUA (1225 5075);
FORCEPROP 1 LAST PART_NUMBER H44441-003
J 0
(1225 2875);
DISPLAY 0.617021 (1225 2875);
PAINT BLUE (1225 2875);
FORCEPROP 1 LAST MATERIAL SCONN
J 0
(1225 5025);
DISPLAY 0.617021 (1225 5025);
PAINT SKYBLUE (1225 5025);
FORCEPROP 2 LASTPIN (2075 4825) $PN 51
J 0
(2085 4835);
DISPLAY 0.617021 (2085 4835);
PAINT ORANGE (2085 4835);
FORCEPROP 2 LASTPIN (2075 4775) $PN 52
J 0
(2085 4785);
DISPLAY 0.617021 (2085 4785);
PAINT ORANGE (2085 4785);
FORCEPROP 2 LASTPIN (2075 4725) $PN 132
J 0
(2085 4735);
DISPLAY 0.617021 (2085 4735);
PAINT ORANGE (2085 4735);
FORCEPROP 2 LASTPIN (2075 4675) $PN 133
J 0
(2085 4685);
DISPLAY 0.617021 (2085 4685);
PAINT ORANGE (2085 4685);
FORCEPROP 2 LASTPIN (2075 4625) $PN 121
J 0
(2085 4635);
DISPLAY 0.617021 (2085 4635);
PAINT ORANGE (2085 4635);
FORCEPROP 2 LASTPIN (2075 4575) $PN 122
J 0
(2085 4585);
DISPLAY 0.617021 (2085 4585);
PAINT ORANGE (2085 4585);
FORCEPROP 2 LASTPIN (2075 4525) $PN 110
J 0
(2085 4535);
DISPLAY 0.617021 (2085 4535);
PAINT ORANGE (2085 4535);
FORCEPROP 2 LASTPIN (2075 4475) $PN 111
J 0
(2085 4485);
DISPLAY 0.617021 (2085 4485);
PAINT ORANGE (2085 4485);
FORCEPROP 2 LASTPIN (2075 4425) $PN 99
J 0
(2085 4435);
DISPLAY 0.617021 (2085 4435);
PAINT ORANGE (2085 4435);
FORCEPROP 2 LASTPIN (2075 4375) $PN 100
J 0
(2085 4385);
DISPLAY 0.617021 (2085 4385);
PAINT ORANGE (2085 4385);
FORCEPROP 2 LASTPIN (2075 4325) $PN 40
J 0
(2085 4335);
DISPLAY 0.617021 (2085 4335);
PAINT ORANGE (2085 4335);
FORCEPROP 2 LASTPIN (2075 4275) $PN 41
J 0
(2085 4285);
DISPLAY 0.617021 (2085 4285);
PAINT ORANGE (2085 4285);
FORCEPROP 2 LASTPIN (2075 4225) $PN 29
J 0
(2085 4235);
DISPLAY 0.617021 (2085 4235);
PAINT ORANGE (2085 4235);
FORCEPROP 2 LASTPIN (2075 4175) $PN 30
J 0
(2085 4185);
DISPLAY 0.617021 (2085 4185);
PAINT ORANGE (2085 4185);
FORCEPROP 2 LASTPIN (2075 4125) $PN 18
J 0
(2085 4135);
DISPLAY 0.617021 (2085 4135);
PAINT ORANGE (2085 4135);
FORCEPROP 2 LASTPIN (2075 4075) $PN 19
J 0
(2085 4085);
DISPLAY 0.617021 (2085 4085);
PAINT ORANGE (2085 4085);
FORCEPROP 2 LASTPIN (2075 4025) $PN 7
J 0
(2085 4035);
DISPLAY 0.617021 (2085 4035);
PAINT ORANGE (2085 4035);
FORCEPROP 2 LASTPIN (2075 3975) $PN 8
J 0
(2085 3985);
DISPLAY 0.617021 (2085 3985);
PAINT ORANGE (2085 3985);
FORCEPROP 2 LASTPIN (2075 3925) $PN 197
J 0
(2085 3935);
DISPLAY 0.617021 (2085 3935);
PAINT ORANGE (2085 3935);
FORCEPROP 2 LASTPIN (2075 3875) $PN 196
J 0
(2085 3885);
DISPLAY 0.617021 (2085 3885);
PAINT ORANGE (2085 3885);
FORCEPROP 2 LASTPIN (2075 3825) $PN 278
J 0
(2085 3835);
DISPLAY 0.617021 (2085 3835);
PAINT ORANGE (2085 3835);
FORCEPROP 2 LASTPIN (2075 3775) $PN 277
J 0
(2085 3785);
DISPLAY 0.617021 (2085 3785);
PAINT ORANGE (2085 3785);
FORCEPROP 2 LASTPIN (2075 3725) $PN 267
J 0
(2085 3735);
DISPLAY 0.617021 (2085 3735);
PAINT ORANGE (2085 3735);
FORCEPROP 2 LASTPIN (2075 3675) $PN 266
J 0
(2085 3685);
DISPLAY 0.617021 (2085 3685);
PAINT ORANGE (2085 3685);
FORCEPROP 2 LASTPIN (2075 3625) $PN 256
J 0
(2085 3635);
DISPLAY 0.617021 (2085 3635);
PAINT ORANGE (2085 3635);
FORCEPROP 2 LASTPIN (2075 3575) $PN 255
J 0
(2085 3585);
DISPLAY 0.617021 (2085 3585);
PAINT ORANGE (2085 3585);
FORCEPROP 2 LASTPIN (2075 3525) $PN 245
J 0
(2085 3535);
DISPLAY 0.617021 (2085 3535);
PAINT ORANGE (2085 3535);
FORCEPROP 2 LASTPIN (2075 3475) $PN 244
J 0
(2085 3485);
DISPLAY 0.617021 (2085 3485);
PAINT ORANGE (2085 3485);
FORCEPROP 2 LASTPIN (2075 3425) $PN 186
J 0
(2085 3435);
DISPLAY 0.617021 (2085 3435);
PAINT ORANGE (2085 3435);
FORCEPROP 2 LASTPIN (2075 3375) $PN 185
J 0
(2085 3385);
DISPLAY 0.617021 (2085 3385);
PAINT ORANGE (2085 3385);
FORCEPROP 2 LASTPIN (2075 3325) $PN 175
J 0
(2085 3335);
DISPLAY 0.617021 (2085 3335);
PAINT ORANGE (2085 3335);
FORCEPROP 2 LASTPIN (2075 3275) $PN 174
J 0
(2085 3285);
DISPLAY 0.617021 (2085 3285);
PAINT ORANGE (2085 3285);
FORCEPROP 2 LASTPIN (2075 3225) $PN 164
J 0
(2085 3235);
DISPLAY 0.617021 (2085 3235);
PAINT ORANGE (2085 3235);
FORCEPROP 2 LASTPIN (2075 3175) $PN 163
J 0
(2085 3185);
DISPLAY 0.617021 (2085 3185);
PAINT ORANGE (2085 3185);
FORCEPROP 2 LASTPIN (2075 3125) $PN 153
J 0
(2085 3135);
DISPLAY 0.617021 (2085 3135);
PAINT ORANGE (2085 3135);
FORCEPROP 2 LASTPIN (2075 3075) $PN 152
J 0
(2085 3085);
DISPLAY 0.617021 (2085 3085);
PAINT ORANGE (2085 3085);
FORCEPROP 1 LAST PACK_TYPE PIP
J 0
(1225 5125);
PAINT SKYBLUE (1225 5125);
DISPLAY INVISIBLE (1225 5125);
FORCEPROP 2 LAST BOM_COST MEM
J 0
(1625 3975);
PAINT ORANGE (1625 3975);
DISPLAY INVISIBLE (1625 3975);
FORCEPROP 2 LAST CDS_LIB mstr_sconn
J 0
(1625 3975);
PAINT ORANGE (1625 3975);
DISPLAY INVISIBLE (1625 3975);
FORCEPROP 2 LAST SEC_TYPE PIP
J 0
(1225 5125);
DISPLAY 1.021277 (1225 5125);
PAINT ORANGE (1225 5125);
DISPLAY INVISIBLE (1225 5125);
FORCEPROP 2 LAST SEC 2
J 0
(1225 5125);
DISPLAY 0.680851 (1225 5125);
PAINT MONO (1225 5125);
DISPLAY INVISIBLE (1225 5125);
FORCEPROP 2 LAST CDS_LOCATION J9L2
J 0
(1225 5075);
DISPLAY 0.617021 (1225 5075);
PAINT AQUA (1225 5075);
DISPLAY INVISIBLE (1225 5075);
FORCEPROP 1 LAST PATH I100
J 0
(1625 5025);
PAINT GREEN (1625 5025);
DISPLAY INVISIBLE (1625 5025);
FORCEPROP 2 LAST ROOM DDR4_CH_L
J 0
(1225 5175);
PAINT ORANGE (1225 5175);
DISPLAY INVISIBLE (1225 5175);
FORCEADD OFFPAGE..1
(-2225 4625);
FORCEPROP 2 LAST $XR0 61 
J 0
(-2476 4625);
DISPLAY 0.638298 (-2476 4625);
PAINT MONO (-2476 4625);
FORCEPROP 2 LAST $XR1 85 
J 0
(-2566 4625);
DISPLAY 0.638298 (-2566 4625);
PAINT MONO (-2566 4625);
FORCEPROP 2 LAST CDS_LIB mstr_standard
J 0
(-2225 4625);
DISPLAY 0.787234 (-2225 4625);
PAINT MONO (-2225 4625);
DISPLAY INVISIBLE (-2225 4625);
FORCEPROP 1 LAST OFFPAGE TRUE
J 0
(-1900 4500);
DISPLAY 0.936170 (-1900 4500);
PAINT GREEN (-1900 4500);
DISPLAY INVISIBLE (-1900 4500);
FORCEPROP 1 LAST COMMENT_BODY TRUE
J 0
(-2100 4525);
DISPLAY 0.936170 (-2100 4525);
PAINT GREEN (-2100 4525);
DISPLAY INVISIBLE (-2100 4525);
FORCEPROP 2 LAST PATH I101
J 0
(-2475 4675);
DISPLAY 1.021277 (-2475 4675);
PAINT ORANGE (-2475 4675);
DISPLAY INVISIBLE (-2475 4675);
FORCEADD TAP..6
(-1625 3775);
FORCEPROP 3 LASTPIN (-1575 3775) SIG_NAME M_L_MA<1>
J 0
(-1565 3785);
DISPLAY 0.659574 (-1565 3785);
PAINT MONO (-1565 3785);
DISPLAY INVISIBLE (-1565 3785);
FORCEPROP 1 LASTPIN (-1575 3775) BN 1
J 0
(-1625 3785);
DISPLAY 0.617021 (-1625 3785);
PAINT PINK (-1625 3785);
FORCEPROP 2 LAST CDS_LIB mstr_standard
J 2
(-1625 3775);
DISPLAY 0.787234 (-1625 3775);
PAINT MONO (-1625 3775);
DISPLAY INVISIBLE (-1625 3775);
FORCEPROP 1 LAST BODY_TYPE PLUMBING
J 0
(-1625 3725);
DISPLAY 1.234043 (-1625 3725);
PAINT GREEN (-1625 3725);
DISPLAY INVISIBLE (-1625 3725);
FORCEPROP 1 LAST HDL_TAP TRUE
J 0
(-1300 3650);
DISPLAY 1.234043 (-1300 3650);
PAINT GREEN (-1300 3650);
DISPLAY INVISIBLE (-1300 3650);
FORCEPROP 1 LAST PATH I102
J 0
(-1627 3775);
DISPLAY 0.872340 (-1627 3775);
PAINT GREEN (-1627 3775);
DISPLAY INVISIBLE (-1627 3775);
FORCEADD TAP..6
(-1625 3825);
FORCEPROP 3 LASTPIN (-1575 3825) SIG_NAME M_L_MA<2>
J 0
(-1565 3835);
DISPLAY 0.659574 (-1565 3835);
PAINT MONO (-1565 3835);
DISPLAY INVISIBLE (-1565 3835);
FORCEPROP 1 LASTPIN (-1575 3825) BN 2
J 0
(-1625 3835);
DISPLAY 0.617021 (-1625 3835);
PAINT PINK (-1625 3835);
FORCEPROP 2 LAST CDS_LIB mstr_standard
J 2
(-1625 3825);
DISPLAY 0.787234 (-1625 3825);
PAINT MONO (-1625 3825);
DISPLAY INVISIBLE (-1625 3825);
FORCEPROP 1 LAST BODY_TYPE PLUMBING
J 0
(-1625 3775);
DISPLAY 1.234043 (-1625 3775);
PAINT GREEN (-1625 3775);
DISPLAY INVISIBLE (-1625 3775);
FORCEPROP 1 LAST HDL_TAP TRUE
J 0
(-1300 3700);
DISPLAY 1.234043 (-1300 3700);
PAINT GREEN (-1300 3700);
DISPLAY INVISIBLE (-1300 3700);
FORCEPROP 1 LAST PATH I103
J 0
(-1627 3825);
DISPLAY 0.872340 (-1627 3825);
PAINT GREEN (-1627 3825);
DISPLAY INVISIBLE (-1627 3825);
FORCEADD TAP..6
(-1625 3875);
FORCEPROP 3 LASTPIN (-1575 3875) SIG_NAME M_L_MA<3>
J 0
(-1565 3885);
DISPLAY 0.659574 (-1565 3885);
PAINT MONO (-1565 3885);
DISPLAY INVISIBLE (-1565 3885);
FORCEPROP 1 LASTPIN (-1575 3875) BN 3
J 0
(-1625 3885);
DISPLAY 0.617021 (-1625 3885);
PAINT PINK (-1625 3885);
FORCEPROP 2 LAST CDS_LIB mstr_standard
J 2
(-1625 3875);
DISPLAY 0.787234 (-1625 3875);
PAINT MONO (-1625 3875);
DISPLAY INVISIBLE (-1625 3875);
FORCEPROP 1 LAST BODY_TYPE PLUMBING
J 0
(-1625 3825);
DISPLAY 1.234043 (-1625 3825);
PAINT GREEN (-1625 3825);
DISPLAY INVISIBLE (-1625 3825);
FORCEPROP 1 LAST HDL_TAP TRUE
J 0
(-1300 3750);
DISPLAY 1.234043 (-1300 3750);
PAINT GREEN (-1300 3750);
DISPLAY INVISIBLE (-1300 3750);
FORCEPROP 1 LAST PATH I104
J 0
(-1627 3875);
DISPLAY 0.872340 (-1627 3875);
PAINT GREEN (-1627 3875);
DISPLAY INVISIBLE (-1627 3875);
FORCEADD TAP..6
(-1625 3975);
FORCEPROP 3 LASTPIN (-1575 3975) SIG_NAME M_L_MA<5>
J 0
(-1565 3985);
DISPLAY 0.659574 (-1565 3985);
PAINT MONO (-1565 3985);
DISPLAY INVISIBLE (-1565 3985);
FORCEPROP 1 LASTPIN (-1575 3975) BN 5
J 0
(-1625 3985);
DISPLAY 0.617021 (-1625 3985);
PAINT PINK (-1625 3985);
FORCEPROP 2 LAST CDS_LIB mstr_standard
J 2
(-1625 3975);
DISPLAY 0.787234 (-1625 3975);
PAINT MONO (-1625 3975);
DISPLAY INVISIBLE (-1625 3975);
FORCEPROP 1 LAST BODY_TYPE PLUMBING
J 0
(-1625 3925);
DISPLAY 1.234043 (-1625 3925);
PAINT GREEN (-1625 3925);
DISPLAY INVISIBLE (-1625 3925);
FORCEPROP 1 LAST HDL_TAP TRUE
J 0
(-1300 3850);
DISPLAY 1.234043 (-1300 3850);
PAINT GREEN (-1300 3850);
DISPLAY INVISIBLE (-1300 3850);
FORCEPROP 1 LAST PATH I105
J 0
(-1627 3975);
DISPLAY 0.872340 (-1627 3975);
PAINT GREEN (-1627 3975);
DISPLAY INVISIBLE (-1627 3975);
FORCEADD TAP..6
(-1625 3925);
FORCEPROP 3 LASTPIN (-1575 3925) SIG_NAME M_L_MA<4>
J 0
(-1565 3935);
DISPLAY 0.659574 (-1565 3935);
PAINT MONO (-1565 3935);
DISPLAY INVISIBLE (-1565 3935);
FORCEPROP 1 LASTPIN (-1575 3925) BN 4
J 0
(-1625 3935);
DISPLAY 0.617021 (-1625 3935);
PAINT PINK (-1625 3935);
FORCEPROP 2 LAST CDS_LIB mstr_standard
J 2
(-1625 3925);
DISPLAY 0.787234 (-1625 3925);
PAINT MONO (-1625 3925);
DISPLAY INVISIBLE (-1625 3925);
FORCEPROP 1 LAST BODY_TYPE PLUMBING
J 0
(-1625 3875);
DISPLAY 1.234043 (-1625 3875);
PAINT GREEN (-1625 3875);
DISPLAY INVISIBLE (-1625 3875);
FORCEPROP 1 LAST HDL_TAP TRUE
J 0
(-1300 3800);
DISPLAY 1.234043 (-1300 3800);
PAINT GREEN (-1300 3800);
DISPLAY INVISIBLE (-1300 3800);
FORCEPROP 1 LAST PATH I106
J 0
(-1627 3925);
DISPLAY 0.872340 (-1627 3925);
PAINT GREEN (-1627 3925);
DISPLAY INVISIBLE (-1627 3925);
FORCEADD TAP..6
(-1625 4025);
FORCEPROP 3 LASTPIN (-1575 4025) SIG_NAME M_L_MA<6>
J 0
(-1565 4035);
DISPLAY 0.659574 (-1565 4035);
PAINT MONO (-1565 4035);
DISPLAY INVISIBLE (-1565 4035);
FORCEPROP 1 LASTPIN (-1575 4025) BN 6
J 0
(-1625 4035);
DISPLAY 0.617021 (-1625 4035);
PAINT PINK (-1625 4035);
FORCEPROP 2 LAST CDS_LIB mstr_standard
J 2
(-1625 4025);
DISPLAY 0.787234 (-1625 4025);
PAINT MONO (-1625 4025);
DISPLAY INVISIBLE (-1625 4025);
FORCEPROP 1 LAST BODY_TYPE PLUMBING
J 0
(-1625 3975);
DISPLAY 1.234043 (-1625 3975);
PAINT GREEN (-1625 3975);
DISPLAY INVISIBLE (-1625 3975);
FORCEPROP 1 LAST HDL_TAP TRUE
J 0
(-1300 3900);
DISPLAY 1.234043 (-1300 3900);
PAINT GREEN (-1300 3900);
DISPLAY INVISIBLE (-1300 3900);
FORCEPROP 1 LAST PATH I107
J 0
(-1627 4025);
DISPLAY 0.872340 (-1627 4025);
PAINT GREEN (-1627 4025);
DISPLAY INVISIBLE (-1627 4025);
FORCEADD TAP..6
(-1625 4125);
FORCEPROP 3 LASTPIN (-1575 4125) SIG_NAME M_L_MA<8>
J 0
(-1565 4135);
DISPLAY 0.659574 (-1565 4135);
PAINT MONO (-1565 4135);
DISPLAY INVISIBLE (-1565 4135);
FORCEPROP 1 LASTPIN (-1575 4125) BN 8
J 0
(-1625 4135);
DISPLAY 0.617021 (-1625 4135);
PAINT PINK (-1625 4135);
FORCEPROP 2 LAST CDS_LIB mstr_standard
J 2
(-1625 4125);
DISPLAY 0.787234 (-1625 4125);
PAINT MONO (-1625 4125);
DISPLAY INVISIBLE (-1625 4125);
FORCEPROP 1 LAST BODY_TYPE PLUMBING
J 0
(-1625 4075);
DISPLAY 1.234043 (-1625 4075);
PAINT GREEN (-1625 4075);
DISPLAY INVISIBLE (-1625 4075);
FORCEPROP 1 LAST HDL_TAP TRUE
J 0
(-1300 4000);
DISPLAY 1.234043 (-1300 4000);
PAINT GREEN (-1300 4000);
DISPLAY INVISIBLE (-1300 4000);
FORCEPROP 1 LAST PATH I108
J 0
(-1627 4125);
DISPLAY 0.872340 (-1627 4125);
PAINT GREEN (-1627 4125);
DISPLAY INVISIBLE (-1627 4125);
FORCEADD TAP..6
(-1625 4075);
FORCEPROP 3 LASTPIN (-1575 4075) SIG_NAME M_L_MA<7>
J 0
(-1565 4085);
DISPLAY 0.659574 (-1565 4085);
PAINT MONO (-1565 4085);
DISPLAY INVISIBLE (-1565 4085);
FORCEPROP 1 LASTPIN (-1575 4075) BN 7
J 0
(-1625 4085);
DISPLAY 0.617021 (-1625 4085);
PAINT PINK (-1625 4085);
FORCEPROP 2 LAST CDS_LIB mstr_standard
J 2
(-1625 4075);
DISPLAY 0.787234 (-1625 4075);
PAINT MONO (-1625 4075);
DISPLAY INVISIBLE (-1625 4075);
FORCEPROP 1 LAST BODY_TYPE PLUMBING
J 0
(-1625 4025);
DISPLAY 1.234043 (-1625 4025);
PAINT GREEN (-1625 4025);
DISPLAY INVISIBLE (-1625 4025);
FORCEPROP 1 LAST HDL_TAP TRUE
J 0
(-1300 3950);
DISPLAY 1.234043 (-1300 3950);
PAINT GREEN (-1300 3950);
DISPLAY INVISIBLE (-1300 3950);
FORCEPROP 1 LAST PATH I109
J 0
(-1627 4075);
DISPLAY 0.872340 (-1627 4075);
PAINT GREEN (-1627 4075);
DISPLAY INVISIBLE (-1627 4075);
FORCEADD OFFPAGE..6
(-2225 1575);
FORCEPROP 2 LAST $XR0 83 
J 0
(-2474 1575);
DISPLAY 0.638298 (-2474 1575);
PAINT MONO (-2474 1575);
FORCEPROP 2 LAST $XR1 84 
J 0
(-2564 1575);
DISPLAY 0.638298 (-2564 1575);
PAINT MONO (-2564 1575);
FORCEPROP 2 LAST $XR2 85 
J 0
(-2654 1575);
DISPLAY 0.638298 (-2654 1575);
PAINT MONO (-2654 1575);
FORCEPROP 2 LAST $XR3 87 
J 0
(-2744 1575);
DISPLAY 0.638298 (-2744 1575);
PAINT MONO (-2744 1575);
FORCEPROP 2 LAST $XR4 88 
J 0
(-2834 1575);
DISPLAY 0.638298 (-2834 1575);
PAINT MONO (-2834 1575);
FORCEPROP 2 LAST $XR5 99 
J 0
(-2924 1575);
DISPLAY 0.638298 (-2924 1575);
PAINT MONO (-2924 1575);
FORCEPROP 2 LASTPIN (-2175 1575) SIG_NAME SMB_DDR_KLM_VPP_SDA
J 0
(-2135 1585);
DISPLAY 0.617021 (-2135 1585);
PAINT ORANGE (-2135 1585);
FORCEPROP 2 LAST CDS_LIB mstr_standard
J 0
(-2225 1575);
DISPLAY 0.787234 (-2225 1575);
PAINT MONO (-2225 1575);
DISPLAY INVISIBLE (-2225 1575);
FORCEPROP 1 LAST OFFPAGE TRUE
J 0
(-1900 1450);
DISPLAY 0.936170 (-1900 1450);
PAINT GREEN (-1900 1450);
DISPLAY INVISIBLE (-1900 1450);
FORCEPROP 1 LAST COMMENT_BODY TRUE
J 0
(-2125 1500);
DISPLAY 0.936170 (-2125 1500);
PAINT GREEN (-2125 1500);
DISPLAY INVISIBLE (-2125 1500);
FORCEPROP 2 LAST PATH I11
J 0
(-2450 1625);
DISPLAY 1.021277 (-2450 1625);
PAINT ORANGE (-2450 1625);
DISPLAY INVISIBLE (-2450 1625);
FORCEADD TAP..6
(-1625 4175);
FORCEPROP 3 LASTPIN (-1575 4175) SIG_NAME M_L_MA<9>
J 0
(-1565 4185);
DISPLAY 0.659574 (-1565 4185);
PAINT MONO (-1565 4185);
DISPLAY INVISIBLE (-1565 4185);
FORCEPROP 1 LASTPIN (-1575 4175) BN 9
J 0
(-1625 4185);
DISPLAY 0.617021 (-1625 4185);
PAINT PINK (-1625 4185);
FORCEPROP 2 LAST CDS_LIB mstr_standard
J 2
(-1625 4175);
DISPLAY 0.787234 (-1625 4175);
PAINT MONO (-1625 4175);
DISPLAY INVISIBLE (-1625 4175);
FORCEPROP 1 LAST BODY_TYPE PLUMBING
J 0
(-1625 4125);
DISPLAY 1.234043 (-1625 4125);
PAINT GREEN (-1625 4125);
DISPLAY INVISIBLE (-1625 4125);
FORCEPROP 1 LAST HDL_TAP TRUE
J 0
(-1300 4050);
DISPLAY 1.234043 (-1300 4050);
PAINT GREEN (-1300 4050);
DISPLAY INVISIBLE (-1300 4050);
FORCEPROP 1 LAST PATH I110
J 0
(-1627 4175);
DISPLAY 0.872340 (-1627 4175);
PAINT GREEN (-1627 4175);
DISPLAY INVISIBLE (-1627 4175);
FORCEADD TAP..6
(-1625 4225);
FORCEPROP 3 LASTPIN (-1575 4225) SIG_NAME M_L_MA<10>
J 0
(-1565 4235);
DISPLAY 0.659574 (-1565 4235);
PAINT MONO (-1565 4235);
DISPLAY INVISIBLE (-1565 4235);
FORCEPROP 1 LASTPIN (-1575 4225) BN 10
J 0
(-1625 4235);
DISPLAY 0.617021 (-1625 4235);
PAINT PINK (-1625 4235);
FORCEPROP 2 LAST CDS_LIB mstr_standard
J 2
(-1625 4225);
DISPLAY 0.787234 (-1625 4225);
PAINT MONO (-1625 4225);
DISPLAY INVISIBLE (-1625 4225);
FORCEPROP 1 LAST BODY_TYPE PLUMBING
J 0
(-1625 4175);
DISPLAY 1.234043 (-1625 4175);
PAINT GREEN (-1625 4175);
DISPLAY INVISIBLE (-1625 4175);
FORCEPROP 1 LAST HDL_TAP TRUE
J 0
(-1300 4100);
DISPLAY 1.234043 (-1300 4100);
PAINT GREEN (-1300 4100);
DISPLAY INVISIBLE (-1300 4100);
FORCEPROP 1 LAST PATH I111
J 0
(-1627 4225);
DISPLAY 0.872340 (-1627 4225);
PAINT GREEN (-1627 4225);
DISPLAY INVISIBLE (-1627 4225);
FORCEADD TAP..6
(-1625 4275);
FORCEPROP 3 LASTPIN (-1575 4275) SIG_NAME M_L_MA<11>
J 0
(-1565 4285);
DISPLAY 0.659574 (-1565 4285);
PAINT MONO (-1565 4285);
DISPLAY INVISIBLE (-1565 4285);
FORCEPROP 1 LASTPIN (-1575 4275) BN 11
J 0
(-1625 4285);
DISPLAY 0.617021 (-1625 4285);
PAINT PINK (-1625 4285);
FORCEPROP 2 LAST CDS_LIB mstr_standard
J 2
(-1625 4275);
DISPLAY 0.787234 (-1625 4275);
PAINT MONO (-1625 4275);
DISPLAY INVISIBLE (-1625 4275);
FORCEPROP 1 LAST BODY_TYPE PLUMBING
J 0
(-1625 4225);
DISPLAY 1.234043 (-1625 4225);
PAINT GREEN (-1625 4225);
DISPLAY INVISIBLE (-1625 4225);
FORCEPROP 1 LAST HDL_TAP TRUE
J 0
(-1300 4150);
DISPLAY 1.234043 (-1300 4150);
PAINT GREEN (-1300 4150);
DISPLAY INVISIBLE (-1300 4150);
FORCEPROP 1 LAST PATH I112
J 0
(-1627 4275);
DISPLAY 0.872340 (-1627 4275);
PAINT GREEN (-1627 4275);
DISPLAY INVISIBLE (-1627 4275);
FORCEADD TAP..6
(-1625 4375);
FORCEPROP 3 LASTPIN (-1575 4375) SIG_NAME M_L_MA<13>
J 0
(-1565 4385);
DISPLAY 0.659574 (-1565 4385);
PAINT MONO (-1565 4385);
DISPLAY INVISIBLE (-1565 4385);
FORCEPROP 1 LASTPIN (-1575 4375) BN 13
J 0
(-1625 4385);
DISPLAY 0.617021 (-1625 4385);
PAINT PINK (-1625 4385);
FORCEPROP 2 LAST CDS_LIB mstr_standard
J 2
(-1625 4375);
DISPLAY 0.787234 (-1625 4375);
PAINT MONO (-1625 4375);
DISPLAY INVISIBLE (-1625 4375);
FORCEPROP 1 LAST BODY_TYPE PLUMBING
J 0
(-1625 4325);
DISPLAY 1.234043 (-1625 4325);
PAINT GREEN (-1625 4325);
DISPLAY INVISIBLE (-1625 4325);
FORCEPROP 1 LAST HDL_TAP TRUE
J 0
(-1300 4250);
DISPLAY 1.234043 (-1300 4250);
PAINT GREEN (-1300 4250);
DISPLAY INVISIBLE (-1300 4250);
FORCEPROP 1 LAST PATH I113
J 0
(-1627 4375);
DISPLAY 0.872340 (-1627 4375);
PAINT GREEN (-1627 4375);
DISPLAY INVISIBLE (-1627 4375);
FORCEADD TAP..6
(-1625 4325);
FORCEPROP 3 LASTPIN (-1575 4325) SIG_NAME M_L_MA<12>
J 0
(-1565 4335);
DISPLAY 0.659574 (-1565 4335);
PAINT MONO (-1565 4335);
DISPLAY INVISIBLE (-1565 4335);
FORCEPROP 1 LASTPIN (-1575 4325) BN 12
J 0
(-1625 4335);
DISPLAY 0.617021 (-1625 4335);
PAINT PINK (-1625 4335);
FORCEPROP 2 LAST CDS_LIB mstr_standard
J 2
(-1625 4325);
DISPLAY 0.787234 (-1625 4325);
PAINT MONO (-1625 4325);
DISPLAY INVISIBLE (-1625 4325);
FORCEPROP 1 LAST BODY_TYPE PLUMBING
J 0
(-1625 4275);
DISPLAY 1.234043 (-1625 4275);
PAINT GREEN (-1625 4275);
DISPLAY INVISIBLE (-1625 4275);
FORCEPROP 1 LAST HDL_TAP TRUE
J 0
(-1300 4200);
DISPLAY 1.234043 (-1300 4200);
PAINT GREEN (-1300 4200);
DISPLAY INVISIBLE (-1300 4200);
FORCEPROP 1 LAST PATH I114
J 0
(-1627 4325);
DISPLAY 0.872340 (-1627 4325);
PAINT GREEN (-1627 4325);
DISPLAY INVISIBLE (-1627 4325);
FORCEADD TAP..6
(-1625 4425);
FORCEPROP 3 LASTPIN (-1575 4425) SIG_NAME M_L_MA<14>
J 0
(-1565 4435);
DISPLAY 0.659574 (-1565 4435);
PAINT MONO (-1565 4435);
DISPLAY INVISIBLE (-1565 4435);
FORCEPROP 1 LASTPIN (-1575 4425) BN 14
J 0
(-1625 4435);
DISPLAY 0.617021 (-1625 4435);
PAINT PINK (-1625 4435);
FORCEPROP 2 LAST CDS_LIB mstr_standard
J 2
(-1625 4425);
DISPLAY 0.787234 (-1625 4425);
PAINT MONO (-1625 4425);
DISPLAY INVISIBLE (-1625 4425);
FORCEPROP 1 LAST BODY_TYPE PLUMBING
J 0
(-1625 4375);
DISPLAY 1.234043 (-1625 4375);
PAINT GREEN (-1625 4375);
DISPLAY INVISIBLE (-1625 4375);
FORCEPROP 1 LAST HDL_TAP TRUE
J 0
(-1300 4300);
DISPLAY 1.234043 (-1300 4300);
PAINT GREEN (-1300 4300);
DISPLAY INVISIBLE (-1300 4300);
FORCEPROP 1 LAST PATH I115
J 0
(-1627 4425);
DISPLAY 0.872340 (-1627 4425);
PAINT GREEN (-1627 4425);
DISPLAY INVISIBLE (-1627 4425);
FORCEADD TAP..6
(-1625 4475);
FORCEPROP 3 LASTPIN (-1575 4475) SIG_NAME M_L_MA<15>
J 0
(-1565 4485);
DISPLAY 0.659574 (-1565 4485);
PAINT MONO (-1565 4485);
DISPLAY INVISIBLE (-1565 4485);
FORCEPROP 1 LASTPIN (-1575 4475) BN 15
J 0
(-1625 4485);
DISPLAY 0.617021 (-1625 4485);
PAINT PINK (-1625 4485);
FORCEPROP 2 LAST CDS_LIB mstr_standard
J 2
(-1625 4475);
DISPLAY 0.787234 (-1625 4475);
PAINT MONO (-1625 4475);
DISPLAY INVISIBLE (-1625 4475);
FORCEPROP 1 LAST BODY_TYPE PLUMBING
J 0
(-1625 4425);
DISPLAY 1.234043 (-1625 4425);
PAINT GREEN (-1625 4425);
DISPLAY INVISIBLE (-1625 4425);
FORCEPROP 1 LAST HDL_TAP TRUE
J 0
(-1300 4350);
DISPLAY 1.234043 (-1300 4350);
PAINT GREEN (-1300 4350);
DISPLAY INVISIBLE (-1300 4350);
FORCEPROP 1 LAST PATH I116
J 0
(-1627 4475);
DISPLAY 0.872340 (-1627 4475);
PAINT GREEN (-1627 4475);
DISPLAY INVISIBLE (-1627 4475);
FORCEADD TAP..6
(-1625 4525);
FORCEPROP 3 LASTPIN (-1575 4525) SIG_NAME M_L_MA<16>
J 0
(-1565 4535);
DISPLAY 0.659574 (-1565 4535);
PAINT MONO (-1565 4535);
DISPLAY INVISIBLE (-1565 4535);
FORCEPROP 1 LASTPIN (-1575 4525) BN 16
J 0
(-1625 4535);
DISPLAY 0.617021 (-1625 4535);
PAINT PINK (-1625 4535);
FORCEPROP 2 LAST CDS_LIB mstr_standard
J 2
(-1625 4525);
DISPLAY 0.787234 (-1625 4525);
PAINT MONO (-1625 4525);
DISPLAY INVISIBLE (-1625 4525);
FORCEPROP 1 LAST BODY_TYPE PLUMBING
J 0
(-1625 4475);
DISPLAY 1.234043 (-1625 4475);
PAINT GREEN (-1625 4475);
DISPLAY INVISIBLE (-1625 4475);
FORCEPROP 1 LAST HDL_TAP TRUE
J 0
(-1300 4400);
DISPLAY 1.234043 (-1300 4400);
PAINT GREEN (-1300 4400);
DISPLAY INVISIBLE (-1300 4400);
FORCEPROP 1 LAST PATH I117
J 0
(-1627 4525);
DISPLAY 0.872340 (-1627 4525);
PAINT GREEN (-1627 4525);
DISPLAY INVISIBLE (-1627 4525);
FORCEADD TAP..6
(-1625 4575);
FORCEPROP 3 LASTPIN (-1575 4575) SIG_NAME M_L_MA<17>
J 0
(-1565 4585);
DISPLAY 0.659574 (-1565 4585);
PAINT MONO (-1565 4585);
DISPLAY INVISIBLE (-1565 4585);
FORCEPROP 1 LASTPIN (-1575 4575) BN 17
J 0
(-1625 4585);
DISPLAY 0.617021 (-1625 4585);
PAINT PINK (-1625 4585);
FORCEPROP 2 LAST CDS_LIB mstr_standard
J 0
(-1625 4575);
DISPLAY 0.787234 (-1625 4575);
PAINT MONO (-1625 4575);
DISPLAY INVISIBLE (-1625 4575);
FORCEPROP 1 LAST BODY_TYPE PLUMBING
J 0
(-1625 4525);
DISPLAY 1.234043 (-1625 4525);
PAINT GREEN (-1625 4525);
DISPLAY INVISIBLE (-1625 4525);
FORCEPROP 1 LAST HDL_TAP TRUE
J 0
(-1300 4450);
DISPLAY 1.234043 (-1300 4450);
PAINT GREEN (-1300 4450);
DISPLAY INVISIBLE (-1300 4450);
FORCEPROP 1 LAST PATH I118
J 0
(-1627 4575);
DISPLAY 0.872340 (-1627 4575);
PAINT GREEN (-1627 4575);
DISPLAY INVISIBLE (-1627 4575);
FORCEADD TAP..6
R 2
(-125 3925);
FORCEPROP 3 LASTPIN (-175 3925) SIG_NAME M_L_DQ<50>
J 0
(-165 3935);
DISPLAY 0.659574 (-165 3935);
PAINT MONO (-165 3935);
DISPLAY INVISIBLE (-165 3935);
FORCEPROP 1 LASTPIN (-175 3925) BN 50
J 2
(-125 3935);
DISPLAY 0.617021 (-125 3935);
PAINT PINK (-125 3935);
FORCEPROP 2 LAST CDS_LIB mstr_standard
J 2
(-125 3925);
DISPLAY 0.787234 (-125 3925);
PAINT MONO (-125 3925);
DISPLAY INVISIBLE (-125 3925);
FORCEPROP 1 LAST BODY_TYPE PLUMBING
J 2
(-125 3875);
DISPLAY 1.234043 (-125 3875);
PAINT GREEN (-125 3875);
DISPLAY INVISIBLE (-125 3875);
FORCEPROP 1 LAST HDL_TAP TRUE
J 2
(-450 3800);
DISPLAY 1.234043 (-450 3800);
PAINT GREEN (-450 3800);
DISPLAY INVISIBLE (-450 3800);
FORCEPROP 1 LAST PATH I119
J 2
(-123 3925);
DISPLAY 0.872340 (-123 3925);
PAINT GREEN (-123 3925);
DISPLAY INVISIBLE (-123 3925);
FORCEADD SCONN288_H44441003..1
(-875 2925);
FORCEPROP 1 LAST LOCATION J9L2
J 0
(-1325 4825);
DISPLAY 0.617021 (-1325 4825);
PAINT AQUA (-1325 4825);
FORCEPROP 1 LAST PART_NUMBER H44441-003
J 0
(-1325 925);
DISPLAY 0.617021 (-1325 925);
PAINT BLUE (-1325 925);
FORCEPROP 1 LAST MATERIAL SCONN
J 0
(-1325 4775);
DISPLAY 0.617021 (-1325 4775);
PAINT SKYBLUE (-1325 4775);
FORCEPROP 2 LASTPIN (-1375 1425) $PN 146
J 2
(-1385 1435);
DISPLAY 0.617021 (-1385 1435);
PAINT ORANGE (-1385 1435);
FORCEPROP 2 LASTPIN (-1375 1775) $PN 284
J 2
(-1385 1785);
DISPLAY 0.617021 (-1385 1785);
PAINT ORANGE (-1385 1785);
FORCEPROP 2 LASTPIN (-1375 1575) $PN 285
J 2
(-1385 1585);
DISPLAY 0.617021 (-1385 1585);
PAINT ORANGE (-1385 1585);
FORCEPROP 2 LASTPIN (-1375 1525) $PN 141
J 2
(-1385 1535);
DISPLAY 0.617021 (-1385 1535);
PAINT ORANGE (-1385 1535);
FORCEPROP 2 LASTPIN (-1375 1125) $PN 230
J 2
(-1385 1135);
DISPLAY 0.617021 (-1385 1135);
PAINT ORANGE (-1385 1135);
FORCEPROP 2 LASTPIN (-1375 1725) $PN 238
J 2
(-1385 1735);
DISPLAY 0.617021 (-1385 1735);
PAINT ORANGE (-1385 1735);
FORCEPROP 2 LASTPIN (-1375 1675) $PN 140
J 2
(-1385 1685);
DISPLAY 0.617021 (-1385 1685);
PAINT ORANGE (-1385 1685);
FORCEPROP 2 LASTPIN (-1375 1625) $PN 139
J 2
(-1385 1635);
DISPLAY 0.617021 (-1385 1635);
PAINT ORANGE (-1385 1635);
FORCEPROP 2 LASTPIN (-1375 3075) $PN 237
J 2
(-1385 3085);
DISPLAY 0.617021 (-1385 3085);
PAINT ORANGE (-1385 3085);
FORCEPROP 2 LASTPIN (-1375 3025) $PN 93
J 2
(-1385 3035);
DISPLAY 0.617021 (-1385 3035);
PAINT ORANGE (-1385 3035);
FORCEPROP 2 LASTPIN (-1375 2975) $PN 89
J 2
(-1385 2985);
DISPLAY 0.617021 (-1385 2985);
PAINT ORANGE (-1385 2985);
FORCEPROP 2 LASTPIN (-1375 2925) $PN 84
J 2
(-1385 2935);
DISPLAY 0.617021 (-1385 2935);
PAINT ORANGE (-1385 2935);
FORCEPROP 2 LASTPIN (-1375 1325) $PN 144
J 2
(-1385 1335);
DISPLAY 0.617021 (-1385 1335);
PAINT ORANGE (-1385 1335);
FORCEPROP 2 LASTPIN (-1375 1275) $PN 227
J 2
(-1385 1285);
DISPLAY 0.617021 (-1385 1285);
PAINT ORANGE (-1385 1285);
FORCEPROP 2 LASTPIN (-1375 1225) $PN 205
J 2
(-1385 1235);
DISPLAY 0.617021 (-1385 1235);
PAINT ORANGE (-1385 1235);
FORCEPROP 2 LASTPIN (-1375 2025) $PN 58
J 2
(-1385 2035);
DISPLAY 0.617021 (-1385 2035);
PAINT ORANGE (-1385 2035);
FORCEPROP 2 LASTPIN (-1375 2075) $PN 222
J 2
(-1385 2085);
DISPLAY 0.617021 (-1385 2085);
PAINT ORANGE (-1385 2085);
FORCEPROP 2 LASTPIN (-1375 2675) $PN 91
J 2
(-1385 2685);
DISPLAY 0.617021 (-1385 2685);
PAINT ORANGE (-1385 2685);
FORCEPROP 2 LASTPIN (-1375 2625) $PN 87
J 2
(-1385 2635);
DISPLAY 0.617021 (-1385 2635);
PAINT ORANGE (-1385 2635);
FORCEPROP 2 LASTPIN (-1375 1975) $PN 78
J 2
(-1385 1985);
DISPLAY 0.617021 (-1385 1985);
PAINT ORANGE (-1385 1985);
FORCEPROP 2 LASTPIN (-375 4575) $PN 280
J 0
(-365 4585);
DISPLAY 0.617021 (-365 4585);
PAINT ORANGE (-365 4585);
FORCEPROP 2 LASTPIN (-375 4525) $PN 135
J 0
(-365 4535);
DISPLAY 0.617021 (-365 4535);
PAINT ORANGE (-365 4535);
FORCEPROP 2 LASTPIN (-375 4475) $PN 273
J 0
(-365 4485);
DISPLAY 0.617021 (-365 4485);
PAINT ORANGE (-365 4485);
FORCEPROP 2 LASTPIN (-375 4425) $PN 128
J 0
(-365 4435);
DISPLAY 0.617021 (-365 4435);
PAINT ORANGE (-365 4435);
FORCEPROP 2 LASTPIN (-375 4375) $PN 282
J 0
(-365 4385);
DISPLAY 0.617021 (-365 4385);
PAINT ORANGE (-365 4385);
FORCEPROP 2 LASTPIN (-375 4325) $PN 137
J 0
(-365 4335);
DISPLAY 0.617021 (-365 4335);
PAINT ORANGE (-365 4335);
FORCEPROP 2 LASTPIN (-375 4275) $PN 275
J 0
(-365 4285);
DISPLAY 0.617021 (-365 4285);
PAINT ORANGE (-365 4285);
FORCEPROP 2 LASTPIN (-375 4225) $PN 130
J 0
(-365 4235);
DISPLAY 0.617021 (-365 4235);
PAINT ORANGE (-365 4235);
FORCEPROP 2 LASTPIN (-375 4175) $PN 269
J 0
(-365 4185);
DISPLAY 0.617021 (-365 4185);
PAINT ORANGE (-365 4185);
FORCEPROP 2 LASTPIN (-375 4125) $PN 124
J 0
(-365 4135);
DISPLAY 0.617021 (-365 4135);
PAINT ORANGE (-365 4135);
FORCEPROP 2 LASTPIN (-375 4075) $PN 262
J 0
(-365 4085);
DISPLAY 0.617021 (-365 4085);
PAINT ORANGE (-365 4085);
FORCEPROP 2 LASTPIN (-375 4025) $PN 117
J 0
(-365 4035);
DISPLAY 0.617021 (-365 4035);
PAINT ORANGE (-365 4035);
FORCEPROP 2 LASTPIN (-375 3975) $PN 271
J 0
(-365 3985);
DISPLAY 0.617021 (-365 3985);
PAINT ORANGE (-365 3985);
FORCEPROP 2 LASTPIN (-375 3925) $PN 126
J 0
(-365 3935);
DISPLAY 0.617021 (-365 3935);
PAINT ORANGE (-365 3935);
FORCEPROP 2 LASTPIN (-375 3875) $PN 264
J 0
(-365 3885);
DISPLAY 0.617021 (-365 3885);
PAINT ORANGE (-365 3885);
FORCEPROP 2 LASTPIN (-375 3825) $PN 119
J 0
(-365 3835);
DISPLAY 0.617021 (-365 3835);
PAINT ORANGE (-365 3835);
FORCEPROP 2 LASTPIN (-375 3775) $PN 258
J 0
(-365 3785);
DISPLAY 0.617021 (-365 3785);
PAINT ORANGE (-365 3785);
FORCEPROP 2 LASTPIN (-375 3725) $PN 113
J 0
(-365 3735);
DISPLAY 0.617021 (-365 3735);
PAINT ORANGE (-365 3735);
FORCEPROP 2 LASTPIN (-375 3675) $PN 251
J 0
(-365 3685);
DISPLAY 0.617021 (-365 3685);
PAINT ORANGE (-365 3685);
FORCEPROP 2 LASTPIN (-375 3625) $PN 106
J 0
(-365 3635);
DISPLAY 0.617021 (-365 3635);
PAINT ORANGE (-365 3635);
FORCEPROP 2 LASTPIN (-375 3575) $PN 260
J 0
(-365 3585);
DISPLAY 0.617021 (-365 3585);
PAINT ORANGE (-365 3585);
FORCEPROP 2 LASTPIN (-375 3525) $PN 115
J 0
(-365 3535);
DISPLAY 0.617021 (-365 3535);
PAINT ORANGE (-365 3535);
FORCEPROP 2 LASTPIN (-375 3475) $PN 253
J 0
(-365 3485);
DISPLAY 0.617021 (-365 3485);
PAINT ORANGE (-365 3485);
FORCEPROP 2 LASTPIN (-375 3425) $PN 108
J 0
(-365 3435);
DISPLAY 0.617021 (-365 3435);
PAINT ORANGE (-365 3435);
FORCEPROP 2 LASTPIN (-375 3375) $PN 247
J 0
(-365 3385);
DISPLAY 0.617021 (-365 3385);
PAINT ORANGE (-365 3385);
FORCEPROP 2 LASTPIN (-375 3325) $PN 102
J 0
(-365 3335);
DISPLAY 0.617021 (-365 3335);
PAINT ORANGE (-365 3335);
FORCEPROP 2 LASTPIN (-375 3275) $PN 240
J 0
(-365 3285);
DISPLAY 0.617021 (-365 3285);
PAINT ORANGE (-365 3285);
FORCEPROP 2 LASTPIN (-375 3225) $PN 95
J 0
(-365 3235);
DISPLAY 0.617021 (-365 3235);
PAINT ORANGE (-365 3235);
FORCEPROP 2 LASTPIN (-375 3175) $PN 249
J 0
(-365 3185);
DISPLAY 0.617021 (-365 3185);
PAINT ORANGE (-365 3185);
FORCEPROP 2 LASTPIN (-375 3125) $PN 104
J 0
(-365 3135);
DISPLAY 0.617021 (-365 3135);
PAINT ORANGE (-365 3135);
FORCEPROP 2 LASTPIN (-375 3075) $PN 242
J 0
(-365 3085);
DISPLAY 0.617021 (-365 3085);
PAINT ORANGE (-365 3085);
FORCEPROP 2 LASTPIN (-375 3025) $PN 97
J 0
(-365 3035);
DISPLAY 0.617021 (-365 3035);
PAINT ORANGE (-365 3035);
FORCEPROP 2 LASTPIN (-375 2975) $PN 188
J 0
(-365 2985);
DISPLAY 0.617021 (-365 2985);
PAINT ORANGE (-365 2985);
FORCEPROP 2 LASTPIN (-375 2925) $PN 43
J 0
(-365 2935);
DISPLAY 0.617021 (-365 2935);
PAINT ORANGE (-365 2935);
FORCEPROP 2 LASTPIN (-375 2875) $PN 181
J 0
(-365 2885);
DISPLAY 0.617021 (-365 2885);
PAINT ORANGE (-365 2885);
FORCEPROP 2 LASTPIN (-375 2825) $PN 36
J 0
(-365 2835);
DISPLAY 0.617021 (-365 2835);
PAINT ORANGE (-365 2835);
FORCEPROP 2 LASTPIN (-375 2775) $PN 190
J 0
(-365 2785);
DISPLAY 0.617021 (-365 2785);
PAINT ORANGE (-365 2785);
FORCEPROP 2 LASTPIN (-375 2725) $PN 45
J 0
(-365 2735);
DISPLAY 0.617021 (-365 2735);
PAINT ORANGE (-365 2735);
FORCEPROP 2 LASTPIN (-375 2675) $PN 183
J 0
(-365 2685);
DISPLAY 0.617021 (-365 2685);
PAINT ORANGE (-365 2685);
FORCEPROP 2 LASTPIN (-375 2625) $PN 38
J 0
(-365 2635);
DISPLAY 0.617021 (-365 2635);
PAINT ORANGE (-365 2635);
FORCEPROP 2 LASTPIN (-375 2575) $PN 177
J 0
(-365 2585);
DISPLAY 0.617021 (-365 2585);
PAINT ORANGE (-365 2585);
FORCEPROP 2 LASTPIN (-375 2525) $PN 32
J 0
(-365 2535);
DISPLAY 0.617021 (-365 2535);
PAINT ORANGE (-365 2535);
FORCEPROP 2 LASTPIN (-375 2475) $PN 170
J 0
(-365 2485);
DISPLAY 0.617021 (-365 2485);
PAINT ORANGE (-365 2485);
FORCEPROP 2 LASTPIN (-375 2425) $PN 25
J 0
(-365 2435);
DISPLAY 0.617021 (-365 2435);
PAINT ORANGE (-365 2435);
FORCEPROP 2 LASTPIN (-375 2375) $PN 179
J 0
(-365 2385);
DISPLAY 0.617021 (-365 2385);
PAINT ORANGE (-365 2385);
FORCEPROP 2 LASTPIN (-375 2325) $PN 34
J 0
(-365 2335);
DISPLAY 0.617021 (-365 2335);
PAINT ORANGE (-365 2335);
FORCEPROP 2 LASTPIN (-375 2275) $PN 172
J 0
(-365 2285);
DISPLAY 0.617021 (-365 2285);
PAINT ORANGE (-365 2285);
FORCEPROP 2 LASTPIN (-375 2225) $PN 27
J 0
(-365 2235);
DISPLAY 0.617021 (-365 2235);
PAINT ORANGE (-365 2235);
FORCEPROP 2 LASTPIN (-375 2175) $PN 166
J 0
(-365 2185);
DISPLAY 0.617021 (-365 2185);
PAINT ORANGE (-365 2185);
FORCEPROP 2 LASTPIN (-375 2125) $PN 21
J 0
(-365 2135);
DISPLAY 0.617021 (-365 2135);
PAINT ORANGE (-365 2135);
FORCEPROP 2 LASTPIN (-375 2075) $PN 159
J 0
(-365 2085);
DISPLAY 0.617021 (-365 2085);
PAINT ORANGE (-365 2085);
FORCEPROP 2 LASTPIN (-375 2025) $PN 14
J 0
(-365 2035);
DISPLAY 0.617021 (-365 2035);
PAINT ORANGE (-365 2035);
FORCEPROP 2 LASTPIN (-375 1975) $PN 168
J 0
(-365 1985);
DISPLAY 0.617021 (-365 1985);
PAINT ORANGE (-365 1985);
FORCEPROP 2 LASTPIN (-375 1925) $PN 23
J 0
(-365 1935);
DISPLAY 0.617021 (-365 1935);
PAINT ORANGE (-365 1935);
FORCEPROP 2 LASTPIN (-375 1875) $PN 161
J 0
(-365 1885);
DISPLAY 0.617021 (-365 1885);
PAINT ORANGE (-365 1885);
FORCEPROP 2 LASTPIN (-375 1825) $PN 16
J 0
(-365 1835);
DISPLAY 0.617021 (-365 1835);
PAINT ORANGE (-365 1835);
FORCEPROP 2 LASTPIN (-375 1775) $PN 155
J 0
(-365 1785);
DISPLAY 0.617021 (-365 1785);
PAINT ORANGE (-365 1785);
FORCEPROP 2 LASTPIN (-375 1725) $PN 10
J 0
(-365 1735);
DISPLAY 0.617021 (-365 1735);
PAINT ORANGE (-365 1735);
FORCEPROP 2 LASTPIN (-375 1675) $PN 148
J 0
(-365 1685);
DISPLAY 0.617021 (-365 1685);
PAINT ORANGE (-365 1685);
FORCEPROP 2 LASTPIN (-375 1625) $PN 3
J 0
(-365 1635);
DISPLAY 0.617021 (-365 1635);
PAINT ORANGE (-365 1635);
FORCEPROP 2 LASTPIN (-375 1575) $PN 157
J 0
(-365 1585);
DISPLAY 0.617021 (-365 1585);
PAINT ORANGE (-365 1585);
FORCEPROP 2 LASTPIN (-375 1525) $PN 12
J 0
(-365 1535);
DISPLAY 0.617021 (-365 1535);
PAINT ORANGE (-365 1535);
FORCEPROP 2 LASTPIN (-375 1475) $PN 150
J 0
(-365 1485);
DISPLAY 0.617021 (-365 1485);
PAINT ORANGE (-365 1485);
FORCEPROP 2 LASTPIN (-375 1425) $PN 5
J 0
(-365 1435);
DISPLAY 0.617021 (-365 1435);
PAINT ORANGE (-365 1435);
FORCEPROP 2 LASTPIN (-1375 2825) $PN 203
J 2
(-1385 2835);
DISPLAY 0.617021 (-1385 2835);
PAINT ORANGE (-1385 2835);
FORCEPROP 2 LASTPIN (-1375 2775) $PN 60
J 2
(-1385 2785);
DISPLAY 0.617021 (-1385 2785);
PAINT ORANGE (-1385 2785);
FORCEPROP 2 LASTPIN (-1375 3375) $PN 218
J 2
(-1385 3385);
DISPLAY 0.617021 (-1385 3385);
PAINT ORANGE (-1385 3385);
FORCEPROP 2 LASTPIN (-1375 3325) $PN 219
J 2
(-1385 3335);
DISPLAY 0.617021 (-1385 3335);
PAINT ORANGE (-1385 3335);
FORCEPROP 2 LASTPIN (-1375 3275) $PN 74
J 2
(-1385 3285);
DISPLAY 0.617021 (-1385 3285);
PAINT ORANGE (-1385 3285);
FORCEPROP 2 LASTPIN (-1375 3225) $PN 75
J 2
(-1385 3235);
DISPLAY 0.617021 (-1385 3235);
PAINT ORANGE (-1385 3235);
FORCEPROP 2 LASTPIN (-1375 2525) $PN 199
J 2
(-1385 2535);
DISPLAY 0.617021 (-1385 2535);
PAINT ORANGE (-1385 2535);
FORCEPROP 2 LASTPIN (-1375 2475) $PN 54
J 2
(-1385 2485);
DISPLAY 0.617021 (-1385 2485);
PAINT ORANGE (-1385 2485);
FORCEPROP 2 LASTPIN (-1375 2425) $PN 192
J 2
(-1385 2435);
DISPLAY 0.617021 (-1385 2435);
PAINT ORANGE (-1385 2435);
FORCEPROP 2 LASTPIN (-1375 2375) $PN 47
J 2
(-1385 2385);
DISPLAY 0.617021 (-1385 2385);
PAINT ORANGE (-1385 2385);
FORCEPROP 2 LASTPIN (-1375 2325) $PN 201
J 2
(-1385 2335);
DISPLAY 0.617021 (-1385 2335);
PAINT ORANGE (-1385 2335);
FORCEPROP 2 LASTPIN (-1375 2275) $PN 56
J 2
(-1385 2285);
DISPLAY 0.617021 (-1385 2285);
PAINT ORANGE (-1385 2285);
FORCEPROP 2 LASTPIN (-1375 2225) $PN 194
J 2
(-1385 2235);
DISPLAY 0.617021 (-1385 2235);
PAINT ORANGE (-1385 2235);
FORCEPROP 2 LASTPIN (-1375 2175) $PN 49
J 2
(-1385 2185);
DISPLAY 0.617021 (-1385 2185);
PAINT ORANGE (-1385 2185);
FORCEPROP 2 LASTPIN (-1375 3125) $PN 235
J 2
(-1385 3135);
DISPLAY 0.617021 (-1385 3135);
PAINT ORANGE (-1385 3135);
FORCEPROP 2 LASTPIN (-1375 3525) $PN 207
J 2
(-1385 3535);
DISPLAY 0.617021 (-1385 3535);
PAINT ORANGE (-1385 3535);
FORCEPROP 2 LASTPIN (-1375 3475) $PN 63
J 2
(-1385 3485);
DISPLAY 0.617021 (-1385 3485);
PAINT ORANGE (-1385 3485);
FORCEPROP 2 LASTPIN (-1375 3625) $PN 224
J 2
(-1385 3635);
DISPLAY 0.617021 (-1385 3635);
PAINT ORANGE (-1385 3635);
FORCEPROP 2 LASTPIN (-1375 3575) $PN 81
J 2
(-1385 3585);
DISPLAY 0.617021 (-1385 3585);
PAINT ORANGE (-1385 3585);
FORCEPROP 2 LASTPIN (-1375 1925) $PN 208
J 2
(-1385 1935);
DISPLAY 0.617021 (-1385 1935);
PAINT ORANGE (-1385 1935);
FORCEPROP 2 LASTPIN (-1375 1875) $PN 62
J 2
(-1385 1885);
DISPLAY 0.617021 (-1385 1885);
PAINT ORANGE (-1385 1885);
FORCEPROP 2 LASTPIN (-1375 4575) $PN 234
J 2
(-1385 4585);
DISPLAY 0.617021 (-1385 4585);
PAINT ORANGE (-1385 4585);
FORCEPROP 2 LASTPIN (-1375 4525) $PN 82
J 2
(-1385 4535);
DISPLAY 0.617021 (-1385 4535);
PAINT ORANGE (-1385 4535);
FORCEPROP 2 LASTPIN (-1375 4475) $PN 86
J 2
(-1385 4485);
DISPLAY 0.617021 (-1385 4485);
PAINT ORANGE (-1385 4485);
FORCEPROP 2 LASTPIN (-1375 4425) $PN 228
J 2
(-1385 4435);
DISPLAY 0.617021 (-1385 4435);
PAINT ORANGE (-1385 4435);
FORCEPROP 2 LASTPIN (-1375 4375) $PN 232
J 2
(-1385 4385);
DISPLAY 0.617021 (-1385 4385);
PAINT ORANGE (-1385 4385);
FORCEPROP 2 LASTPIN (-1375 4325) $PN 65
J 2
(-1385 4335);
DISPLAY 0.617021 (-1385 4335);
PAINT ORANGE (-1385 4335);
FORCEPROP 2 LASTPIN (-1375 4275) $PN 210
J 2
(-1385 4285);
DISPLAY 0.617021 (-1385 4285);
PAINT ORANGE (-1385 4285);
FORCEPROP 2 LASTPIN (-1375 4225) $PN 225
J 2
(-1385 4235);
DISPLAY 0.617021 (-1385 4235);
PAINT ORANGE (-1385 4235);
FORCEPROP 2 LASTPIN (-1375 4175) $PN 66
J 2
(-1385 4185);
DISPLAY 0.617021 (-1385 4185);
PAINT ORANGE (-1385 4185);
FORCEPROP 2 LASTPIN (-1375 4125) $PN 68
J 2
(-1385 4135);
DISPLAY 0.617021 (-1385 4135);
PAINT ORANGE (-1385 4135);
FORCEPROP 2 LASTPIN (-1375 4075) $PN 211
J 2
(-1385 4085);
DISPLAY 0.617021 (-1385 4085);
PAINT ORANGE (-1385 4085);
FORCEPROP 2 LASTPIN (-1375 4025) $PN 69
J 2
(-1385 4035);
DISPLAY 0.617021 (-1385 4035);
PAINT ORANGE (-1385 4035);
FORCEPROP 2 LASTPIN (-1375 3975) $PN 213
J 2
(-1385 3985);
DISPLAY 0.617021 (-1385 3985);
PAINT ORANGE (-1385 3985);
FORCEPROP 2 LASTPIN (-1375 3925) $PN 214
J 2
(-1385 3935);
DISPLAY 0.617021 (-1385 3935);
PAINT ORANGE (-1385 3935);
FORCEPROP 2 LASTPIN (-1375 3875) $PN 71
J 2
(-1385 3885);
DISPLAY 0.617021 (-1385 3885);
PAINT ORANGE (-1385 3885);
FORCEPROP 2 LASTPIN (-1375 3825) $PN 216
J 2
(-1385 3835);
DISPLAY 0.617021 (-1385 3835);
PAINT ORANGE (-1385 3835);
FORCEPROP 2 LASTPIN (-1375 3775) $PN 72
J 2
(-1385 3785);
DISPLAY 0.617021 (-1385 3785);
PAINT ORANGE (-1385 3785);
FORCEPROP 2 LASTPIN (-1375 3725) $PN 79
J 2
(-1385 3735);
DISPLAY 0.617021 (-1385 3735);
PAINT ORANGE (-1385 3735);
FORCEPROP 1 LAST PACK_TYPE PIP
J 0
(-1325 4875);
PAINT SKYBLUE (-1325 4875);
DISPLAY INVISIBLE (-1325 4875);
FORCEPROP 2 LAST BOM_COST MEM
J 0
(-875 2925);
PAINT ORANGE (-875 2925);
DISPLAY INVISIBLE (-875 2925);
FORCEPROP 2 LAST CDS_LIB mstr_sconn
J 0
(-875 2925);
PAINT ORANGE (-875 2925);
DISPLAY INVISIBLE (-875 2925);
FORCEPROP 2 LAST SEC_TYPE PIP
J 0
(-1325 4875);
DISPLAY 1.021277 (-1325 4875);
PAINT ORANGE (-1325 4875);
DISPLAY INVISIBLE (-1325 4875);
FORCEPROP 2 LAST SEC 1
J 0
(-1325 4875);
DISPLAY 0.680851 (-1325 4875);
PAINT MONO (-1325 4875);
DISPLAY INVISIBLE (-1325 4875);
FORCEPROP 2 LAST CDS_LOCATION J9L2
J 0
(-1325 4825);
DISPLAY 0.617021 (-1325 4825);
PAINT AQUA (-1325 4825);
DISPLAY INVISIBLE (-1325 4825);
FORCEPROP 1 LAST PATH I12
J 0
(-875 4775);
PAINT GREEN (-875 4775);
DISPLAY INVISIBLE (-875 4775);
FORCEPROP 2 LAST ROOM DDR4_CH_L
J 0
(-875 2925);
PAINT ORANGE (-875 2925);
DISPLAY INVISIBLE (-875 2925);
FORCEADD TAP..6
R 2
(-125 3975);
FORCEPROP 3 LASTPIN (-175 3975) SIG_NAME M_L_DQ<51>
J 0
(-165 3985);
DISPLAY 0.659574 (-165 3985);
PAINT MONO (-165 3985);
DISPLAY INVISIBLE (-165 3985);
FORCEPROP 1 LASTPIN (-175 3975) BN 51
J 2
(-125 3985);
DISPLAY 0.617021 (-125 3985);
PAINT PINK (-125 3985);
FORCEPROP 2 LAST CDS_LIB mstr_standard
J 2
(-125 3975);
DISPLAY 0.787234 (-125 3975);
PAINT MONO (-125 3975);
DISPLAY INVISIBLE (-125 3975);
FORCEPROP 1 LAST BODY_TYPE PLUMBING
J 2
(-125 3925);
DISPLAY 1.234043 (-125 3925);
PAINT GREEN (-125 3925);
DISPLAY INVISIBLE (-125 3925);
FORCEPROP 1 LAST HDL_TAP TRUE
J 2
(-450 3850);
DISPLAY 1.234043 (-450 3850);
PAINT GREEN (-450 3850);
DISPLAY INVISIBLE (-450 3850);
FORCEPROP 1 LAST PATH I120
J 2
(-123 3975);
DISPLAY 0.872340 (-123 3975);
PAINT GREEN (-123 3975);
DISPLAY INVISIBLE (-123 3975);
FORCEADD TAP..6
R 2
(-125 3875);
FORCEPROP 3 LASTPIN (-175 3875) SIG_NAME M_L_DQ<49>
J 0
(-165 3885);
DISPLAY 0.659574 (-165 3885);
PAINT MONO (-165 3885);
DISPLAY INVISIBLE (-165 3885);
FORCEPROP 1 LASTPIN (-175 3875) BN 49
J 2
(-125 3885);
DISPLAY 0.617021 (-125 3885);
PAINT PINK (-125 3885);
FORCEPROP 2 LAST CDS_LIB mstr_standard
J 2
(-125 3875);
DISPLAY 0.787234 (-125 3875);
PAINT MONO (-125 3875);
DISPLAY INVISIBLE (-125 3875);
FORCEPROP 1 LAST BODY_TYPE PLUMBING
J 2
(-125 3825);
DISPLAY 1.234043 (-125 3825);
PAINT GREEN (-125 3825);
DISPLAY INVISIBLE (-125 3825);
FORCEPROP 1 LAST HDL_TAP TRUE
J 2
(-450 3750);
DISPLAY 1.234043 (-450 3750);
PAINT GREEN (-450 3750);
DISPLAY INVISIBLE (-450 3750);
FORCEPROP 1 LAST PATH I121
J 2
(-123 3875);
DISPLAY 0.872340 (-123 3875);
PAINT GREEN (-123 3875);
DISPLAY INVISIBLE (-123 3875);
FORCEADD TAP..6
R 2
(-125 3775);
FORCEPROP 3 LASTPIN (-175 3775) SIG_NAME M_L_DQ<47>
J 0
(-165 3785);
DISPLAY 0.659574 (-165 3785);
PAINT MONO (-165 3785);
DISPLAY INVISIBLE (-165 3785);
FORCEPROP 1 LASTPIN (-175 3775) BN 47
J 2
(-125 3785);
DISPLAY 0.617021 (-125 3785);
PAINT PINK (-125 3785);
FORCEPROP 2 LAST CDS_LIB mstr_standard
J 2
(-125 3775);
DISPLAY 0.787234 (-125 3775);
PAINT MONO (-125 3775);
DISPLAY INVISIBLE (-125 3775);
FORCEPROP 1 LAST BODY_TYPE PLUMBING
J 2
(-125 3725);
DISPLAY 1.234043 (-125 3725);
PAINT GREEN (-125 3725);
DISPLAY INVISIBLE (-125 3725);
FORCEPROP 1 LAST HDL_TAP TRUE
J 2
(-450 3650);
DISPLAY 1.234043 (-450 3650);
PAINT GREEN (-450 3650);
DISPLAY INVISIBLE (-450 3650);
FORCEPROP 1 LAST PATH I122
J 2
(-123 3775);
DISPLAY 0.872340 (-123 3775);
PAINT GREEN (-123 3775);
DISPLAY INVISIBLE (-123 3775);
FORCEADD TAP..6
R 2
(-125 3825);
FORCEPROP 3 LASTPIN (-175 3825) SIG_NAME M_L_DQ<48>
J 0
(-165 3835);
DISPLAY 0.659574 (-165 3835);
PAINT MONO (-165 3835);
DISPLAY INVISIBLE (-165 3835);
FORCEPROP 1 LASTPIN (-175 3825) BN 48
J 2
(-125 3835);
DISPLAY 0.617021 (-125 3835);
PAINT PINK (-125 3835);
FORCEPROP 2 LAST CDS_LIB mstr_standard
J 2
(-125 3825);
DISPLAY 0.787234 (-125 3825);
PAINT MONO (-125 3825);
DISPLAY INVISIBLE (-125 3825);
FORCEPROP 1 LAST BODY_TYPE PLUMBING
J 2
(-125 3775);
DISPLAY 1.234043 (-125 3775);
PAINT GREEN (-125 3775);
DISPLAY INVISIBLE (-125 3775);
FORCEPROP 1 LAST HDL_TAP TRUE
J 2
(-450 3700);
DISPLAY 1.234043 (-450 3700);
PAINT GREEN (-450 3700);
DISPLAY INVISIBLE (-450 3700);
FORCEPROP 1 LAST PATH I123
J 2
(-123 3825);
DISPLAY 0.872340 (-123 3825);
PAINT GREEN (-123 3825);
DISPLAY INVISIBLE (-123 3825);
FORCEADD TAP..6
R 2
(-125 4025);
FORCEPROP 3 LASTPIN (-175 4025) SIG_NAME M_L_DQ<52>
J 0
(-165 4035);
DISPLAY 0.659574 (-165 4035);
PAINT MONO (-165 4035);
DISPLAY INVISIBLE (-165 4035);
FORCEPROP 1 LASTPIN (-175 4025) BN 52
J 2
(-125 4035);
DISPLAY 0.617021 (-125 4035);
PAINT PINK (-125 4035);
FORCEPROP 2 LAST CDS_LIB mstr_standard
J 2
(-125 4025);
DISPLAY 0.787234 (-125 4025);
PAINT MONO (-125 4025);
DISPLAY INVISIBLE (-125 4025);
FORCEPROP 1 LAST BODY_TYPE PLUMBING
J 2
(-125 3975);
DISPLAY 1.234043 (-125 3975);
PAINT GREEN (-125 3975);
DISPLAY INVISIBLE (-125 3975);
FORCEPROP 1 LAST HDL_TAP TRUE
J 2
(-450 3900);
DISPLAY 1.234043 (-450 3900);
PAINT GREEN (-450 3900);
DISPLAY INVISIBLE (-450 3900);
FORCEPROP 1 LAST PATH I124
J 2
(-123 4025);
DISPLAY 0.872340 (-123 4025);
PAINT GREEN (-123 4025);
DISPLAY INVISIBLE (-123 4025);
FORCEADD TAP..6
R 2
(-125 4175);
FORCEPROP 3 LASTPIN (-175 4175) SIG_NAME M_L_DQ<55>
J 0
(-165 4185);
DISPLAY 0.659574 (-165 4185);
PAINT MONO (-165 4185);
DISPLAY INVISIBLE (-165 4185);
FORCEPROP 1 LASTPIN (-175 4175) BN 55
J 2
(-125 4185);
DISPLAY 0.617021 (-125 4185);
PAINT PINK (-125 4185);
FORCEPROP 2 LAST CDS_LIB mstr_standard
J 2
(-125 4175);
DISPLAY 0.787234 (-125 4175);
PAINT MONO (-125 4175);
DISPLAY INVISIBLE (-125 4175);
FORCEPROP 1 LAST BODY_TYPE PLUMBING
J 2
(-125 4125);
DISPLAY 1.234043 (-125 4125);
PAINT GREEN (-125 4125);
DISPLAY INVISIBLE (-125 4125);
FORCEPROP 1 LAST HDL_TAP TRUE
J 2
(-450 4050);
DISPLAY 1.234043 (-450 4050);
PAINT GREEN (-450 4050);
DISPLAY INVISIBLE (-450 4050);
FORCEPROP 1 LAST PATH I125
J 2
(-123 4175);
DISPLAY 0.872340 (-123 4175);
PAINT GREEN (-123 4175);
DISPLAY INVISIBLE (-123 4175);
FORCEADD TAP..6
R 2
(-125 4225);
FORCEPROP 3 LASTPIN (-175 4225) SIG_NAME M_L_DQ<56>
J 0
(-165 4235);
DISPLAY 0.659574 (-165 4235);
PAINT MONO (-165 4235);
DISPLAY INVISIBLE (-165 4235);
FORCEPROP 1 LASTPIN (-175 4225) BN 56
J 2
(-125 4235);
DISPLAY 0.617021 (-125 4235);
PAINT PINK (-125 4235);
FORCEPROP 2 LAST CDS_LIB mstr_standard
J 2
(-125 4225);
DISPLAY 0.787234 (-125 4225);
PAINT MONO (-125 4225);
DISPLAY INVISIBLE (-125 4225);
FORCEPROP 1 LAST BODY_TYPE PLUMBING
J 2
(-125 4175);
DISPLAY 1.234043 (-125 4175);
PAINT GREEN (-125 4175);
DISPLAY INVISIBLE (-125 4175);
FORCEPROP 1 LAST HDL_TAP TRUE
J 2
(-450 4100);
DISPLAY 1.234043 (-450 4100);
PAINT GREEN (-450 4100);
DISPLAY INVISIBLE (-450 4100);
FORCEPROP 1 LAST PATH I126
J 2
(-123 4225);
DISPLAY 0.872340 (-123 4225);
PAINT GREEN (-123 4225);
DISPLAY INVISIBLE (-123 4225);
FORCEADD TAP..6
R 2
(-125 4275);
FORCEPROP 3 LASTPIN (-175 4275) SIG_NAME M_L_DQ<57>
J 0
(-165 4285);
DISPLAY 0.659574 (-165 4285);
PAINT MONO (-165 4285);
DISPLAY INVISIBLE (-165 4285);
FORCEPROP 1 LASTPIN (-175 4275) BN 57
J 2
(-125 4285);
DISPLAY 0.617021 (-125 4285);
PAINT PINK (-125 4285);
FORCEPROP 2 LAST CDS_LIB mstr_standard
J 2
(-125 4275);
DISPLAY 0.787234 (-125 4275);
PAINT MONO (-125 4275);
DISPLAY INVISIBLE (-125 4275);
FORCEPROP 1 LAST BODY_TYPE PLUMBING
J 2
(-125 4225);
DISPLAY 1.234043 (-125 4225);
PAINT GREEN (-125 4225);
DISPLAY INVISIBLE (-125 4225);
FORCEPROP 1 LAST HDL_TAP TRUE
J 2
(-450 4150);
DISPLAY 1.234043 (-450 4150);
PAINT GREEN (-450 4150);
DISPLAY INVISIBLE (-450 4150);
FORCEPROP 1 LAST PATH I127
J 2
(-123 4275);
DISPLAY 0.872340 (-123 4275);
PAINT GREEN (-123 4275);
DISPLAY INVISIBLE (-123 4275);
FORCEADD TAP..6
R 2
(-125 4075);
FORCEPROP 3 LASTPIN (-175 4075) SIG_NAME M_L_DQ<53>
J 0
(-165 4085);
DISPLAY 0.659574 (-165 4085);
PAINT MONO (-165 4085);
DISPLAY INVISIBLE (-165 4085);
FORCEPROP 1 LASTPIN (-175 4075) BN 53
J 2
(-125 4085);
DISPLAY 0.617021 (-125 4085);
PAINT PINK (-125 4085);
FORCEPROP 2 LAST CDS_LIB mstr_standard
J 2
(-125 4075);
DISPLAY 0.787234 (-125 4075);
PAINT MONO (-125 4075);
DISPLAY INVISIBLE (-125 4075);
FORCEPROP 1 LAST BODY_TYPE PLUMBING
J 2
(-125 4025);
DISPLAY 1.234043 (-125 4025);
PAINT GREEN (-125 4025);
DISPLAY INVISIBLE (-125 4025);
FORCEPROP 1 LAST HDL_TAP TRUE
J 2
(-450 3950);
DISPLAY 1.234043 (-450 3950);
PAINT GREEN (-450 3950);
DISPLAY INVISIBLE (-450 3950);
FORCEPROP 1 LAST PATH I128
J 2
(-123 4075);
DISPLAY 0.872340 (-123 4075);
PAINT GREEN (-123 4075);
DISPLAY INVISIBLE (-123 4075);
FORCEADD TAP..6
R 2
(-125 4125);
FORCEPROP 3 LASTPIN (-175 4125) SIG_NAME M_L_DQ<54>
J 0
(-165 4135);
DISPLAY 0.659574 (-165 4135);
PAINT MONO (-165 4135);
DISPLAY INVISIBLE (-165 4135);
FORCEPROP 1 LASTPIN (-175 4125) BN 54
J 2
(-125 4135);
DISPLAY 0.617021 (-125 4135);
PAINT PINK (-125 4135);
FORCEPROP 2 LAST CDS_LIB mstr_standard
J 2
(-125 4125);
DISPLAY 0.787234 (-125 4125);
PAINT MONO (-125 4125);
DISPLAY INVISIBLE (-125 4125);
FORCEPROP 1 LAST BODY_TYPE PLUMBING
J 2
(-125 4075);
DISPLAY 1.234043 (-125 4075);
PAINT GREEN (-125 4075);
DISPLAY INVISIBLE (-125 4075);
FORCEPROP 1 LAST HDL_TAP TRUE
J 2
(-450 4000);
DISPLAY 1.234043 (-450 4000);
PAINT GREEN (-450 4000);
DISPLAY INVISIBLE (-450 4000);
FORCEPROP 1 LAST PATH I129
J 2
(-123 4125);
DISPLAY 0.872340 (-123 4125);
PAINT GREEN (-123 4125);
DISPLAY INVISIBLE (-123 4125);
FORCEADD OFFPAGE..1
(-2225 2475);
FORCEPROP 2 LAST $XR0 55 
J 0
(-2476 2475);
DISPLAY 0.638298 (-2476 2475);
PAINT MONO (-2476 2475);
FORCEPROP 2 LAST $XR1 83 
J 0
(-2566 2475);
DISPLAY 0.638298 (-2566 2475);
PAINT MONO (-2566 2475);
FORCEPROP 2 LAST $XR2 84 
J 0
(-2656 2475);
DISPLAY 0.638298 (-2656 2475);
PAINT MONO (-2656 2475);
FORCEPROP 2 LAST $XR3 85 
J 0
(-2746 2475);
DISPLAY 0.638298 (-2746 2475);
PAINT MONO (-2746 2475);
FORCEPROP 2 LAST $XR4 87 
J 0
(-2836 2475);
DISPLAY 0.638298 (-2836 2475);
PAINT MONO (-2836 2475);
FORCEPROP 2 LAST $XR5 88 
J 0
(-2926 2475);
DISPLAY 0.638298 (-2926 2475);
PAINT MONO (-2926 2475);
FORCEPROP 2 LAST CDS_LIB mstr_standard
J 0
(-2225 2475);
DISPLAY 0.787234 (-2225 2475);
PAINT MONO (-2225 2475);
DISPLAY INVISIBLE (-2225 2475);
FORCEPROP 1 LAST OFFPAGE TRUE
J 0
(-1900 2350);
DISPLAY 0.936170 (-1900 2350);
PAINT GREEN (-1900 2350);
DISPLAY INVISIBLE (-1900 2350);
FORCEPROP 1 LAST COMMENT_BODY TRUE
J 0
(-2100 2375);
DISPLAY 0.936170 (-2100 2375);
PAINT GREEN (-2100 2375);
DISPLAY INVISIBLE (-2100 2375);
FORCEPROP 2 LAST PATH I13
J 0
(-2475 2525);
DISPLAY 1.021277 (-2475 2525);
PAINT ORANGE (-2475 2525);
DISPLAY INVISIBLE (-2475 2525);
FORCEADD TAP..6
R 2
(-125 4375);
FORCEPROP 3 LASTPIN (-175 4375) SIG_NAME M_L_DQ<59>
J 0
(-165 4385);
DISPLAY 0.659574 (-165 4385);
PAINT MONO (-165 4385);
DISPLAY INVISIBLE (-165 4385);
FORCEPROP 1 LASTPIN (-175 4375) BN 59
J 2
(-125 4385);
DISPLAY 0.617021 (-125 4385);
PAINT PINK (-125 4385);
FORCEPROP 2 LAST CDS_LIB mstr_standard
J 2
(-125 4375);
DISPLAY 0.787234 (-125 4375);
PAINT MONO (-125 4375);
DISPLAY INVISIBLE (-125 4375);
FORCEPROP 1 LAST BODY_TYPE PLUMBING
J 2
(-125 4325);
DISPLAY 1.234043 (-125 4325);
PAINT GREEN (-125 4325);
DISPLAY INVISIBLE (-125 4325);
FORCEPROP 1 LAST HDL_TAP TRUE
J 2
(-450 4250);
DISPLAY 1.234043 (-450 4250);
PAINT GREEN (-450 4250);
DISPLAY INVISIBLE (-450 4250);
FORCEPROP 1 LAST PATH I130
J 2
(-123 4375);
DISPLAY 0.872340 (-123 4375);
PAINT GREEN (-123 4375);
DISPLAY INVISIBLE (-123 4375);
FORCEADD TAP..6
R 2
(-125 4325);
FORCEPROP 3 LASTPIN (-175 4325) SIG_NAME M_L_DQ<58>
J 0
(-165 4335);
DISPLAY 0.659574 (-165 4335);
PAINT MONO (-165 4335);
DISPLAY INVISIBLE (-165 4335);
FORCEPROP 1 LASTPIN (-175 4325) BN 58
J 2
(-125 4335);
DISPLAY 0.617021 (-125 4335);
PAINT PINK (-125 4335);
FORCEPROP 2 LAST CDS_LIB mstr_standard
J 2
(-125 4325);
DISPLAY 0.787234 (-125 4325);
PAINT MONO (-125 4325);
DISPLAY INVISIBLE (-125 4325);
FORCEPROP 1 LAST BODY_TYPE PLUMBING
J 2
(-125 4275);
DISPLAY 1.234043 (-125 4275);
PAINT GREEN (-125 4275);
DISPLAY INVISIBLE (-125 4275);
FORCEPROP 1 LAST HDL_TAP TRUE
J 2
(-450 4200);
DISPLAY 1.234043 (-450 4200);
PAINT GREEN (-450 4200);
DISPLAY INVISIBLE (-450 4200);
FORCEPROP 1 LAST PATH I131
J 2
(-123 4325);
DISPLAY 0.872340 (-123 4325);
PAINT GREEN (-123 4325);
DISPLAY INVISIBLE (-123 4325);
FORCEADD TAP..6
R 2
(-125 4525);
FORCEPROP 3 LASTPIN (-175 4525) SIG_NAME M_L_DQ<62>
J 0
(-165 4535);
DISPLAY 0.659574 (-165 4535);
PAINT MONO (-165 4535);
DISPLAY INVISIBLE (-165 4535);
FORCEPROP 1 LASTPIN (-175 4525) BN 62
J 2
(-125 4535);
DISPLAY 0.617021 (-125 4535);
PAINT PINK (-125 4535);
FORCEPROP 2 LAST CDS_LIB mstr_standard
J 2
(-125 4525);
DISPLAY 0.787234 (-125 4525);
PAINT MONO (-125 4525);
DISPLAY INVISIBLE (-125 4525);
FORCEPROP 1 LAST BODY_TYPE PLUMBING
J 2
(-125 4475);
DISPLAY 1.234043 (-125 4475);
PAINT GREEN (-125 4475);
DISPLAY INVISIBLE (-125 4475);
FORCEPROP 1 LAST HDL_TAP TRUE
J 2
(-450 4400);
DISPLAY 1.234043 (-450 4400);
PAINT GREEN (-450 4400);
DISPLAY INVISIBLE (-450 4400);
FORCEPROP 1 LAST PATH I132
J 2
(-123 4525);
DISPLAY 0.872340 (-123 4525);
PAINT GREEN (-123 4525);
DISPLAY INVISIBLE (-123 4525);
FORCEADD TAP..6
R 2
(-125 4425);
FORCEPROP 3 LASTPIN (-175 4425) SIG_NAME M_L_DQ<60>
J 0
(-165 4435);
DISPLAY 0.659574 (-165 4435);
PAINT MONO (-165 4435);
DISPLAY INVISIBLE (-165 4435);
FORCEPROP 1 LASTPIN (-175 4425) BN 60
J 2
(-125 4435);
DISPLAY 0.617021 (-125 4435);
PAINT PINK (-125 4435);
FORCEPROP 2 LAST CDS_LIB mstr_standard
J 2
(-125 4425);
DISPLAY 0.787234 (-125 4425);
PAINT MONO (-125 4425);
DISPLAY INVISIBLE (-125 4425);
FORCEPROP 1 LAST BODY_TYPE PLUMBING
J 2
(-125 4375);
DISPLAY 1.234043 (-125 4375);
PAINT GREEN (-125 4375);
DISPLAY INVISIBLE (-125 4375);
FORCEPROP 1 LAST HDL_TAP TRUE
J 2
(-450 4300);
DISPLAY 1.234043 (-450 4300);
PAINT GREEN (-450 4300);
DISPLAY INVISIBLE (-450 4300);
FORCEPROP 1 LAST PATH I133
J 2
(-123 4425);
DISPLAY 0.872340 (-123 4425);
PAINT GREEN (-123 4425);
DISPLAY INVISIBLE (-123 4425);
FORCEADD TAP..6
R 2
(-125 4475);
FORCEPROP 3 LASTPIN (-175 4475) SIG_NAME M_L_DQ<61>
J 0
(-165 4485);
DISPLAY 0.659574 (-165 4485);
PAINT MONO (-165 4485);
DISPLAY INVISIBLE (-165 4485);
FORCEPROP 1 LASTPIN (-175 4475) BN 61
J 2
(-125 4485);
DISPLAY 0.617021 (-125 4485);
PAINT PINK (-125 4485);
FORCEPROP 2 LAST CDS_LIB mstr_standard
J 2
(-125 4475);
DISPLAY 0.787234 (-125 4475);
PAINT MONO (-125 4475);
DISPLAY INVISIBLE (-125 4475);
FORCEPROP 1 LAST BODY_TYPE PLUMBING
J 2
(-125 4425);
DISPLAY 1.234043 (-125 4425);
PAINT GREEN (-125 4425);
DISPLAY INVISIBLE (-125 4425);
FORCEPROP 1 LAST HDL_TAP TRUE
J 2
(-450 4350);
DISPLAY 1.234043 (-450 4350);
PAINT GREEN (-450 4350);
DISPLAY INVISIBLE (-450 4350);
FORCEPROP 1 LAST PATH I134
J 2
(-123 4475);
DISPLAY 0.872340 (-123 4475);
PAINT GREEN (-123 4475);
DISPLAY INVISIBLE (-123 4475);
FORCEADD TAP..6
R 2
(-125 4575);
FORCEPROP 3 LASTPIN (-175 4575) SIG_NAME M_L_DQ<63>
J 0
(-165 4585);
DISPLAY 0.659574 (-165 4585);
PAINT MONO (-165 4585);
DISPLAY INVISIBLE (-165 4585);
FORCEPROP 1 LASTPIN (-175 4575) BN 63
J 2
(-125 4585);
DISPLAY 0.617021 (-125 4585);
PAINT PINK (-125 4585);
FORCEPROP 2 LAST CDS_LIB mstr_standard
J 2
(-125 4575);
DISPLAY 0.787234 (-125 4575);
PAINT MONO (-125 4575);
DISPLAY INVISIBLE (-125 4575);
FORCEPROP 1 LAST BODY_TYPE PLUMBING
J 2
(-125 4525);
DISPLAY 1.234043 (-125 4525);
PAINT GREEN (-125 4525);
DISPLAY INVISIBLE (-125 4525);
FORCEPROP 1 LAST HDL_TAP TRUE
J 2
(-450 4450);
DISPLAY 1.234043 (-450 4450);
PAINT GREEN (-450 4450);
DISPLAY INVISIBLE (-450 4450);
FORCEPROP 1 LAST PATH I135
J 2
(-123 4575);
DISPLAY 0.872340 (-123 4575);
PAINT GREEN (-123 4575);
DISPLAY INVISIBLE (-123 4575);
FORCEADD OFFPAGE..3
(450 4625);
FORCEPROP 2 LAST $XR0 61 
J 0
(664 4625);
DISPLAY 0.638298 (664 4625);
PAINT MONO (664 4625);
FORCEPROP 2 LAST $XR1 85 
J 0
(754 4625);
DISPLAY 0.638298 (754 4625);
PAINT MONO (754 4625);
FORCEPROP 2 LAST CDS_LIB mstr_standard
J 0
(450 4625);
DISPLAY 0.787234 (450 4625);
PAINT MONO (450 4625);
DISPLAY INVISIBLE (450 4625);
FORCEPROP 1 LAST OFFPAGE TRUE
J 0
(775 4500);
DISPLAY 0.936170 (775 4500);
PAINT GREEN (775 4500);
DISPLAY INVISIBLE (775 4500);
FORCEPROP 1 LAST COMMENT_BODY TRUE
J 0
(400 4525);
DISPLAY 0.936170 (400 4525);
PAINT GREEN (400 4525);
DISPLAY INVISIBLE (400 4525);
FORCEPROP 2 LAST PATH I136
J 0
(675 4675);
DISPLAY 1.021277 (675 4675);
PAINT ORANGE (675 4675);
DISPLAY INVISIBLE (675 4675);
FORCEADD GND..1
R 2
(2725 775);
FORCEPROP 3 LASTPIN (2725 825) SIG_NAME GND\g
J 0
(2735 835);
DISPLAY 0.659574 (2735 835);
PAINT MONO (2735 835);
DISPLAY INVISIBLE (2735 835);
FORCEPROP 1 LAST VOLTAGE 0
J 0
(2725 775);
PAINT SKYBLUE (2725 775);
DISPLAY INVISIBLE (2725 775);
FORCEPROP 1 LAST SIZE 1B
J 2
(2650 725);
DISPLAY 1.170213 (2650 725);
PAINT GREEN (2650 725);
DISPLAY INVISIBLE (2650 725);
FORCEPROP 2 LAST CDS_LIB mstr_symbols
J 0
(2725 775);
DISPLAY 0.787234 (2725 775);
PAINT MONO (2725 775);
DISPLAY INVISIBLE (2725 775);
FORCEPROP 2 LAST BOM_COST MEM
J 0
(2725 780);
PAINT ORANGE (2725 780);
DISPLAY INVISIBLE (2725 780);
FORCEPROP 1 LAST BODY_TYPE PLUMBING
J 2
(2770 732);
DISPLAY 0.340426 (2770 732);
PAINT GREEN (2770 732);
DISPLAY INVISIBLE (2770 732);
FORCEPROP 1 LAST PATH I137
J 2
(2650 775);
DISPLAY 0.872340 (2650 775);
PAINT AQUA (2650 775);
DISPLAY INVISIBLE (2650 775);
FORCEPROP 2 LAST ROOM DDR4_CH_D
J 0
(2725 780);
PAINT ORANGE (2725 780);
DISPLAY INVISIBLE (2725 780);
FORCEPROP 1 LAST HDL_POWER GND
J 2
(2725 925);
DISPLAY 0.553191 (2725 925);
PAINT GREEN (2725 925);
DISPLAY INVISIBLE (2725 925);
FORCEADD SCONN288_H44441003..3
(3425 2075);
FORCEPROP 1 LAST LOCATION J9L2
J 0
(2975 3475);
DISPLAY 0.617021 (2975 3475);
PAINT AQUA (2975 3475);
FORCEPROP 1 LAST PART_NUMBER H44441-003
J 0
(2975 725);
DISPLAY 0.617021 (2975 725);
PAINT BLUE (2975 725);
FORCEPROP 1 LAST MATERIAL SCONN
J 0
(2975 3425);
DISPLAY 0.617021 (2975 3425);
PAINT SKYBLUE (2975 3425);
FORCEPROP 2 LASTPIN (2925 3225) $PN 2
J 2
(2915 3235);
DISPLAY 0.617021 (2915 3235);
PAINT ORANGE (2915 3235);
FORCEPROP 2 LASTPIN (2925 3175) $PN 4
J 2
(2915 3185);
DISPLAY 0.617021 (2915 3185);
PAINT ORANGE (2915 3185);
FORCEPROP 2 LASTPIN (2925 3125) $PN 6
J 2
(2915 3135);
DISPLAY 0.617021 (2915 3135);
PAINT ORANGE (2915 3135);
FORCEPROP 2 LASTPIN (2925 3075) $PN 9
J 2
(2915 3085);
DISPLAY 0.617021 (2915 3085);
PAINT ORANGE (2915 3085);
FORCEPROP 2 LASTPIN (2925 3025) $PN 11
J 2
(2915 3035);
DISPLAY 0.617021 (2915 3035);
PAINT ORANGE (2915 3035);
FORCEPROP 2 LASTPIN (2925 2975) $PN 13
J 2
(2915 2985);
DISPLAY 0.617021 (2915 2985);
PAINT ORANGE (2915 2985);
FORCEPROP 2 LASTPIN (2925 2925) $PN 15
J 2
(2915 2935);
DISPLAY 0.617021 (2915 2935);
PAINT ORANGE (2915 2935);
FORCEPROP 2 LASTPIN (2925 2875) $PN 17
J 2
(2915 2885);
DISPLAY 0.617021 (2915 2885);
PAINT ORANGE (2915 2885);
FORCEPROP 2 LASTPIN (2925 2825) $PN 20
J 2
(2915 2835);
DISPLAY 0.617021 (2915 2835);
PAINT ORANGE (2915 2835);
FORCEPROP 2 LASTPIN (2925 2775) $PN 22
J 2
(2915 2785);
DISPLAY 0.617021 (2915 2785);
PAINT ORANGE (2915 2785);
FORCEPROP 2 LASTPIN (2925 2725) $PN 24
J 2
(2915 2735);
DISPLAY 0.617021 (2915 2735);
PAINT ORANGE (2915 2735);
FORCEPROP 2 LASTPIN (2925 2675) $PN 26
J 2
(2915 2685);
DISPLAY 0.617021 (2915 2685);
PAINT ORANGE (2915 2685);
FORCEPROP 2 LASTPIN (2925 2625) $PN 28
J 2
(2915 2635);
DISPLAY 0.617021 (2915 2635);
PAINT ORANGE (2915 2635);
FORCEPROP 2 LASTPIN (2925 2575) $PN 31
J 2
(2915 2585);
DISPLAY 0.617021 (2915 2585);
PAINT ORANGE (2915 2585);
FORCEPROP 2 LASTPIN (2925 2525) $PN 33
J 2
(2915 2535);
DISPLAY 0.617021 (2915 2535);
PAINT ORANGE (2915 2535);
FORCEPROP 2 LASTPIN (2925 2475) $PN 35
J 2
(2915 2485);
DISPLAY 0.617021 (2915 2485);
PAINT ORANGE (2915 2485);
FORCEPROP 2 LASTPIN (2925 2425) $PN 37
J 2
(2915 2435);
DISPLAY 0.617021 (2915 2435);
PAINT ORANGE (2915 2435);
FORCEPROP 2 LASTPIN (2925 2375) $PN 39
J 2
(2915 2385);
DISPLAY 0.617021 (2915 2385);
PAINT ORANGE (2915 2385);
FORCEPROP 2 LASTPIN (2925 2325) $PN 42
J 2
(2915 2335);
DISPLAY 0.617021 (2915 2335);
PAINT ORANGE (2915 2335);
FORCEPROP 2 LASTPIN (2925 2275) $PN 44
J 2
(2915 2285);
DISPLAY 0.617021 (2915 2285);
PAINT ORANGE (2915 2285);
FORCEPROP 2 LASTPIN (2925 2225) $PN 46
J 2
(2915 2235);
DISPLAY 0.617021 (2915 2235);
PAINT ORANGE (2915 2235);
FORCEPROP 2 LASTPIN (2925 2175) $PN 48
J 2
(2915 2185);
DISPLAY 0.617021 (2915 2185);
PAINT ORANGE (2915 2185);
FORCEPROP 2 LASTPIN (2925 2125) $PN 50
J 2
(2915 2135);
DISPLAY 0.617021 (2915 2135);
PAINT ORANGE (2915 2135);
FORCEPROP 2 LASTPIN (2925 2075) $PN 53
J 2
(2915 2085);
DISPLAY 0.617021 (2915 2085);
PAINT ORANGE (2915 2085);
FORCEPROP 2 LASTPIN (2925 2025) $PN 55
J 2
(2915 2035);
DISPLAY 0.617021 (2915 2035);
PAINT ORANGE (2915 2035);
FORCEPROP 2 LASTPIN (2925 1975) $PN 57
J 2
(2915 1985);
DISPLAY 0.617021 (2915 1985);
PAINT ORANGE (2915 1985);
FORCEPROP 2 LASTPIN (2925 1925) $PN 94
J 2
(2915 1935);
DISPLAY 0.617021 (2915 1935);
PAINT ORANGE (2915 1935);
FORCEPROP 2 LASTPIN (2925 1875) $PN 96
J 2
(2915 1885);
DISPLAY 0.617021 (2915 1885);
PAINT ORANGE (2915 1885);
FORCEPROP 2 LASTPIN (2925 1825) $PN 98
J 2
(2915 1835);
DISPLAY 0.617021 (2915 1835);
PAINT ORANGE (2915 1835);
FORCEPROP 2 LASTPIN (2925 1775) $PN 101
J 2
(2915 1785);
DISPLAY 0.617021 (2915 1785);
PAINT ORANGE (2915 1785);
FORCEPROP 2 LASTPIN (2925 1725) $PN 103
J 2
(2915 1735);
DISPLAY 0.617021 (2915 1735);
PAINT ORANGE (2915 1735);
FORCEPROP 2 LASTPIN (2925 1675) $PN 105
J 2
(2915 1685);
DISPLAY 0.617021 (2915 1685);
PAINT ORANGE (2915 1685);
FORCEPROP 2 LASTPIN (2925 1625) $PN 107
J 2
(2915 1635);
DISPLAY 0.617021 (2915 1635);
PAINT ORANGE (2915 1635);
FORCEPROP 2 LASTPIN (2925 1575) $PN 109
J 2
(2915 1585);
DISPLAY 0.617021 (2915 1585);
PAINT ORANGE (2915 1585);
FORCEPROP 2 LASTPIN (2925 1525) $PN 112
J 2
(2915 1535);
DISPLAY 0.617021 (2915 1535);
PAINT ORANGE (2915 1535);
FORCEPROP 2 LASTPIN (2925 1475) $PN 114
J 2
(2915 1485);
DISPLAY 0.617021 (2915 1485);
PAINT ORANGE (2915 1485);
FORCEPROP 2 LASTPIN (2925 1425) $PN 116
J 2
(2915 1435);
DISPLAY 0.617021 (2915 1435);
PAINT ORANGE (2915 1435);
FORCEPROP 2 LASTPIN (2925 1375) $PN 118
J 2
(2915 1385);
DISPLAY 0.617021 (2915 1385);
PAINT ORANGE (2915 1385);
FORCEPROP 2 LASTPIN (2925 1325) $PN 120
J 2
(2915 1335);
DISPLAY 0.617021 (2915 1335);
PAINT ORANGE (2915 1335);
FORCEPROP 2 LASTPIN (2925 1275) $PN 123
J 2
(2915 1285);
DISPLAY 0.617021 (2915 1285);
PAINT ORANGE (2915 1285);
FORCEPROP 2 LASTPIN (2925 1225) $PN 125
J 2
(2915 1235);
DISPLAY 0.617021 (2915 1235);
PAINT ORANGE (2915 1235);
FORCEPROP 2 LASTPIN (2925 1175) $PN 127
J 2
(2915 1185);
DISPLAY 0.617021 (2915 1185);
PAINT ORANGE (2915 1185);
FORCEPROP 2 LASTPIN (2925 1125) $PN 129
J 2
(2915 1135);
DISPLAY 0.617021 (2915 1135);
PAINT ORANGE (2915 1135);
FORCEPROP 2 LASTPIN (2925 1075) $PN 131
J 2
(2915 1085);
DISPLAY 0.617021 (2915 1085);
PAINT ORANGE (2915 1085);
FORCEPROP 2 LASTPIN (2925 1025) $PN 134
J 2
(2915 1035);
DISPLAY 0.617021 (2915 1035);
PAINT ORANGE (2915 1035);
FORCEPROP 2 LASTPIN (2925 975) $PN 136
J 2
(2915 985);
DISPLAY 0.617021 (2915 985);
PAINT ORANGE (2915 985);
FORCEPROP 2 LASTPIN (2925 925) $PN 138
J 2
(2915 935);
DISPLAY 0.617021 (2915 935);
PAINT ORANGE (2915 935);
FORCEPROP 2 LASTPIN (3925 3225) $PN 147
J 0
(3935 3235);
DISPLAY 0.617021 (3935 3235);
PAINT ORANGE (3935 3235);
FORCEPROP 2 LASTPIN (3925 3175) $PN 149
J 0
(3935 3185);
DISPLAY 0.617021 (3935 3185);
PAINT ORANGE (3935 3185);
FORCEPROP 2 LASTPIN (3925 3125) $PN 151
J 0
(3935 3135);
DISPLAY 0.617021 (3935 3135);
PAINT ORANGE (3935 3135);
FORCEPROP 2 LASTPIN (3925 3075) $PN 154
J 0
(3935 3085);
DISPLAY 0.617021 (3935 3085);
PAINT ORANGE (3935 3085);
FORCEPROP 2 LASTPIN (3925 3025) $PN 156
J 0
(3935 3035);
DISPLAY 0.617021 (3935 3035);
PAINT ORANGE (3935 3035);
FORCEPROP 2 LASTPIN (3925 2975) $PN 158
J 0
(3935 2985);
DISPLAY 0.617021 (3935 2985);
PAINT ORANGE (3935 2985);
FORCEPROP 2 LASTPIN (3925 2925) $PN 160
J 0
(3935 2935);
DISPLAY 0.617021 (3935 2935);
PAINT ORANGE (3935 2935);
FORCEPROP 2 LASTPIN (3925 2875) $PN 162
J 0
(3935 2885);
DISPLAY 0.617021 (3935 2885);
PAINT ORANGE (3935 2885);
FORCEPROP 2 LASTPIN (3925 2825) $PN 165
J 0
(3935 2835);
DISPLAY 0.617021 (3935 2835);
PAINT ORANGE (3935 2835);
FORCEPROP 2 LASTPIN (3925 2775) $PN 167
J 0
(3935 2785);
DISPLAY 0.617021 (3935 2785);
PAINT ORANGE (3935 2785);
FORCEPROP 2 LASTPIN (3925 2725) $PN 169
J 0
(3935 2735);
DISPLAY 0.617021 (3935 2735);
PAINT ORANGE (3935 2735);
FORCEPROP 2 LASTPIN (3925 2675) $PN 171
J 0
(3935 2685);
DISPLAY 0.617021 (3935 2685);
PAINT ORANGE (3935 2685);
FORCEPROP 2 LASTPIN (3925 2625) $PN 173
J 0
(3935 2635);
DISPLAY 0.617021 (3935 2635);
PAINT ORANGE (3935 2635);
FORCEPROP 2 LASTPIN (3925 2575) $PN 176
J 0
(3935 2585);
DISPLAY 0.617021 (3935 2585);
PAINT ORANGE (3935 2585);
FORCEPROP 2 LASTPIN (3925 2525) $PN 178
J 0
(3935 2535);
DISPLAY 0.617021 (3935 2535);
PAINT ORANGE (3935 2535);
FORCEPROP 2 LASTPIN (3925 2475) $PN 180
J 0
(3935 2485);
DISPLAY 0.617021 (3935 2485);
PAINT ORANGE (3935 2485);
FORCEPROP 2 LASTPIN (3925 2425) $PN 182
J 0
(3935 2435);
DISPLAY 0.617021 (3935 2435);
PAINT ORANGE (3935 2435);
FORCEPROP 2 LASTPIN (3925 2375) $PN 184
J 0
(3935 2385);
DISPLAY 0.617021 (3935 2385);
PAINT ORANGE (3935 2385);
FORCEPROP 2 LASTPIN (3925 2325) $PN 187
J 0
(3935 2335);
DISPLAY 0.617021 (3935 2335);
PAINT ORANGE (3935 2335);
FORCEPROP 2 LASTPIN (3925 2275) $PN 189
J 0
(3935 2285);
DISPLAY 0.617021 (3935 2285);
PAINT ORANGE (3935 2285);
FORCEPROP 2 LASTPIN (3925 2225) $PN 191
J 0
(3935 2235);
DISPLAY 0.617021 (3935 2235);
PAINT ORANGE (3935 2235);
FORCEPROP 2 LASTPIN (3925 2175) $PN 193
J 0
(3935 2185);
DISPLAY 0.617021 (3935 2185);
PAINT ORANGE (3935 2185);
FORCEPROP 2 LASTPIN (3925 2125) $PN 195
J 0
(3935 2135);
DISPLAY 0.617021 (3935 2135);
PAINT ORANGE (3935 2135);
FORCEPROP 2 LASTPIN (3925 2075) $PN 198
J 0
(3935 2085);
DISPLAY 0.617021 (3935 2085);
PAINT ORANGE (3935 2085);
FORCEPROP 2 LASTPIN (3925 2025) $PN 200
J 0
(3935 2035);
DISPLAY 0.617021 (3935 2035);
PAINT ORANGE (3935 2035);
FORCEPROP 2 LASTPIN (3925 1975) $PN 202
J 0
(3935 1985);
DISPLAY 0.617021 (3935 1985);
PAINT ORANGE (3935 1985);
FORCEPROP 2 LASTPIN (3925 1925) $PN 239
J 0
(3935 1935);
DISPLAY 0.617021 (3935 1935);
PAINT ORANGE (3935 1935);
FORCEPROP 2 LASTPIN (3925 1875) $PN 241
J 0
(3935 1885);
DISPLAY 0.617021 (3935 1885);
PAINT ORANGE (3935 1885);
FORCEPROP 2 LASTPIN (3925 1825) $PN 243
J 0
(3935 1835);
DISPLAY 0.617021 (3935 1835);
PAINT ORANGE (3935 1835);
FORCEPROP 2 LASTPIN (3925 1775) $PN 246
J 0
(3935 1785);
DISPLAY 0.617021 (3935 1785);
PAINT ORANGE (3935 1785);
FORCEPROP 2 LASTPIN (3925 1725) $PN 248
J 0
(3935 1735);
DISPLAY 0.617021 (3935 1735);
PAINT ORANGE (3935 1735);
FORCEPROP 2 LASTPIN (3925 1675) $PN 250
J 0
(3935 1685);
DISPLAY 0.617021 (3935 1685);
PAINT ORANGE (3935 1685);
FORCEPROP 2 LASTPIN (3925 1625) $PN 252
J 0
(3935 1635);
DISPLAY 0.617021 (3935 1635);
PAINT ORANGE (3935 1635);
FORCEPROP 2 LASTPIN (3925 1575) $PN 254
J 0
(3935 1585);
DISPLAY 0.617021 (3935 1585);
PAINT ORANGE (3935 1585);
FORCEPROP 2 LASTPIN (3925 1525) $PN 257
J 0
(3935 1535);
DISPLAY 0.617021 (3935 1535);
PAINT ORANGE (3935 1535);
FORCEPROP 2 LASTPIN (3925 1475) $PN 259
J 0
(3935 1485);
DISPLAY 0.617021 (3935 1485);
PAINT ORANGE (3935 1485);
FORCEPROP 2 LASTPIN (3925 1425) $PN 261
J 0
(3935 1435);
DISPLAY 0.617021 (3935 1435);
PAINT ORANGE (3935 1435);
FORCEPROP 2 LASTPIN (3925 1375) $PN 263
J 0
(3935 1385);
DISPLAY 0.617021 (3935 1385);
PAINT ORANGE (3935 1385);
FORCEPROP 2 LASTPIN (3925 1325) $PN 265
J 0
(3935 1335);
DISPLAY 0.617021 (3935 1335);
PAINT ORANGE (3935 1335);
FORCEPROP 2 LASTPIN (3925 1275) $PN 268
J 0
(3935 1285);
DISPLAY 0.617021 (3935 1285);
PAINT ORANGE (3935 1285);
FORCEPROP 2 LASTPIN (3925 1225) $PN 270
J 0
(3935 1235);
DISPLAY 0.617021 (3935 1235);
PAINT ORANGE (3935 1235);
FORCEPROP 2 LASTPIN (3925 1175) $PN 272
J 0
(3935 1185);
DISPLAY 0.617021 (3935 1185);
PAINT ORANGE (3935 1185);
FORCEPROP 2 LASTPIN (3925 1125) $PN 274
J 0
(3935 1135);
DISPLAY 0.617021 (3935 1135);
PAINT ORANGE (3935 1135);
FORCEPROP 2 LASTPIN (3925 1075) $PN 276
J 0
(3935 1085);
DISPLAY 0.617021 (3935 1085);
PAINT ORANGE (3935 1085);
FORCEPROP 2 LASTPIN (3925 1025) $PN 279
J 0
(3935 1035);
DISPLAY 0.617021 (3935 1035);
PAINT ORANGE (3935 1035);
FORCEPROP 2 LASTPIN (3925 975) $PN 281
J 0
(3935 985);
DISPLAY 0.617021 (3935 985);
PAINT ORANGE (3935 985);
FORCEPROP 2 LASTPIN (3925 925) $PN 283
J 0
(3935 935);
DISPLAY 0.617021 (3935 935);
PAINT ORANGE (3935 935);
FORCEPROP 1 LAST PACK_TYPE PIP
J 0
(2975 3525);
PAINT SKYBLUE (2975 3525);
DISPLAY INVISIBLE (2975 3525);
FORCEPROP 2 LAST BOM_COST MEM
J 0
(3425 2075);
PAINT ORANGE (3425 2075);
DISPLAY INVISIBLE (3425 2075);
FORCEPROP 2 LAST CDS_LIB mstr_sconn
J 0
(3425 2075);
PAINT ORANGE (3425 2075);
DISPLAY INVISIBLE (3425 2075);
FORCEPROP 2 LAST SEC_TYPE PIP
J 0
(2975 3525);
DISPLAY 1.021277 (2975 3525);
PAINT ORANGE (2975 3525);
DISPLAY INVISIBLE (2975 3525);
FORCEPROP 2 LAST SEC 3
J 0
(2975 3525);
DISPLAY 0.680851 (2975 3525);
PAINT MONO (2975 3525);
DISPLAY INVISIBLE (2975 3525);
FORCEPROP 2 LAST CDS_LOCATION J9L2
J 0
(2975 3475);
DISPLAY 0.617021 (2975 3475);
PAINT AQUA (2975 3475);
DISPLAY INVISIBLE (2975 3475);
FORCEPROP 1 LAST PATH I138
J 0
(3425 3425);
PAINT GREEN (3425 3425);
DISPLAY INVISIBLE (3425 3425);
FORCEPROP 2 LAST ROOM DDR4_CH_L
J 0
(3425 2075);
PAINT ORANGE (3425 2075);
DISPLAY INVISIBLE (3425 2075);
FORCEADD OFFPAGE..6
(-2225 2575);
FORCEPROP 2 LAST $XR0 61 
J 0
(-2474 2575);
DISPLAY 0.638298 (-2474 2575);
PAINT MONO (-2474 2575);
FORCEPROP 2 LAST $XR1 85 
J 0
(-2564 2575);
DISPLAY 0.638298 (-2564 2575);
PAINT MONO (-2564 2575);
FORCEPROP 2 LAST CDS_LIB mstr_standard
J 0
(-2225 2575);
DISPLAY 0.787234 (-2225 2575);
PAINT MONO (-2225 2575);
DISPLAY INVISIBLE (-2225 2575);
FORCEPROP 1 LAST OFFPAGE TRUE
J 0
(-1900 2450);
DISPLAY 0.936170 (-1900 2450);
PAINT GREEN (-1900 2450);
DISPLAY INVISIBLE (-1900 2450);
FORCEPROP 1 LAST COMMENT_BODY TRUE
J 0
(-2125 2500);
DISPLAY 0.936170 (-2125 2500);
PAINT GREEN (-2125 2500);
DISPLAY INVISIBLE (-2125 2500);
FORCEPROP 2 LAST PATH I14
J 0
(-2450 2625);
DISPLAY 1.021277 (-2450 2625);
PAINT ORANGE (-2450 2625);
DISPLAY INVISIBLE (-2450 2625);
FORCEADD TAP..6
R 2
(2325 3125);
FORCEPROP 3 LASTPIN (2275 3125) SIG_NAME M_L_DQS_DP<0>
J 0
(2285 3135);
DISPLAY 0.659574 (2285 3135);
PAINT MONO (2285 3135);
DISPLAY INVISIBLE (2285 3135);
FORCEPROP 1 LASTPIN (2275 3125) BN 0
J 2
(2325 3135);
DISPLAY 0.617021 (2325 3135);
PAINT PINK (2325 3135);
FORCEPROP 2 LAST CDS_LIB mstr_standard
J 0
(2325 3125);
DISPLAY 0.787234 (2325 3125);
PAINT MONO (2325 3125);
DISPLAY INVISIBLE (2325 3125);
FORCEPROP 1 LAST BODY_TYPE PLUMBING
J 2
(2325 3075);
DISPLAY 1.234043 (2325 3075);
PAINT GREEN (2325 3075);
DISPLAY INVISIBLE (2325 3075);
FORCEPROP 1 LAST HDL_TAP TRUE
J 2
(2000 3000);
DISPLAY 1.234043 (2000 3000);
PAINT GREEN (2000 3000);
DISPLAY INVISIBLE (2000 3000);
FORCEPROP 1 LAST PATH I142
J 2
(2327 3125);
DISPLAY 0.872340 (2327 3125);
PAINT GREEN (2327 3125);
DISPLAY INVISIBLE (2327 3125);
FORCEADD TAP..6
R 2
(2325 3225);
FORCEPROP 3 LASTPIN (2275 3225) SIG_NAME M_L_DQS_DP<1>
J 0
(2285 3235);
DISPLAY 0.659574 (2285 3235);
PAINT MONO (2285 3235);
DISPLAY INVISIBLE (2285 3235);
FORCEPROP 1 LASTPIN (2275 3225) BN 1
J 2
(2325 3235);
DISPLAY 0.617021 (2325 3235);
PAINT PINK (2325 3235);
FORCEPROP 2 LAST CDS_LIB mstr_standard
J 0
(2325 3225);
DISPLAY 0.787234 (2325 3225);
PAINT MONO (2325 3225);
DISPLAY INVISIBLE (2325 3225);
FORCEPROP 1 LAST BODY_TYPE PLUMBING
J 2
(2325 3175);
DISPLAY 1.234043 (2325 3175);
PAINT GREEN (2325 3175);
DISPLAY INVISIBLE (2325 3175);
FORCEPROP 1 LAST HDL_TAP TRUE
J 2
(2000 3100);
DISPLAY 1.234043 (2000 3100);
PAINT GREEN (2000 3100);
DISPLAY INVISIBLE (2000 3100);
FORCEPROP 1 LAST PATH I143
J 2
(2327 3225);
DISPLAY 0.872340 (2327 3225);
PAINT GREEN (2327 3225);
DISPLAY INVISIBLE (2327 3225);
FORCEADD TAP..6
R 2
(2525 3075);
FORCEPROP 3 LASTPIN (2475 3075) SIG_NAME M_L_DQS_DN<0>
J 0
(2485 3085);
DISPLAY 0.659574 (2485 3085);
PAINT MONO (2485 3085);
DISPLAY INVISIBLE (2485 3085);
FORCEPROP 1 LASTPIN (2475 3075) BN 0
J 2
(2525 3085);
DISPLAY 0.617021 (2525 3085);
PAINT PINK (2525 3085);
FORCEPROP 2 LAST CDS_LIB mstr_standard
J 0
(2525 3075);
DISPLAY 0.787234 (2525 3075);
PAINT MONO (2525 3075);
DISPLAY INVISIBLE (2525 3075);
FORCEPROP 1 LAST BODY_TYPE PLUMBING
J 2
(2525 3025);
DISPLAY 1.234043 (2525 3025);
PAINT GREEN (2525 3025);
DISPLAY INVISIBLE (2525 3025);
FORCEPROP 1 LAST HDL_TAP TRUE
J 2
(2200 2950);
DISPLAY 1.234043 (2200 2950);
PAINT GREEN (2200 2950);
DISPLAY INVISIBLE (2200 2950);
FORCEPROP 1 LAST PATH I144
J 2
(2527 3075);
DISPLAY 0.872340 (2527 3075);
PAINT GREEN (2527 3075);
DISPLAY INVISIBLE (2527 3075);
FORCEADD TAP..6
R 2
(2525 3175);
FORCEPROP 3 LASTPIN (2475 3175) SIG_NAME M_L_DQS_DN<1>
J 0
(2485 3185);
DISPLAY 0.659574 (2485 3185);
PAINT MONO (2485 3185);
DISPLAY INVISIBLE (2485 3185);
FORCEPROP 1 LASTPIN (2475 3175) BN 1
J 2
(2525 3185);
DISPLAY 0.617021 (2525 3185);
PAINT PINK (2525 3185);
FORCEPROP 2 LAST CDS_LIB mstr_standard
J 0
(2525 3175);
DISPLAY 0.787234 (2525 3175);
PAINT MONO (2525 3175);
DISPLAY INVISIBLE (2525 3175);
FORCEPROP 1 LAST BODY_TYPE PLUMBING
J 2
(2525 3125);
DISPLAY 1.234043 (2525 3125);
PAINT GREEN (2525 3125);
DISPLAY INVISIBLE (2525 3125);
FORCEPROP 1 LAST HDL_TAP TRUE
J 2
(2200 3050);
DISPLAY 1.234043 (2200 3050);
PAINT GREEN (2200 3050);
DISPLAY INVISIBLE (2200 3050);
FORCEPROP 1 LAST PATH I145
J 2
(2527 3175);
DISPLAY 0.872340 (2527 3175);
PAINT GREEN (2527 3175);
DISPLAY INVISIBLE (2527 3175);
FORCEADD TAP..6
R 2
(2325 3325);
FORCEPROP 3 LASTPIN (2275 3325) SIG_NAME M_L_DQS_DP<2>
J 0
(2285 3335);
DISPLAY 0.659574 (2285 3335);
PAINT MONO (2285 3335);
DISPLAY INVISIBLE (2285 3335);
FORCEPROP 1 LASTPIN (2275 3325) BN 2
J 2
(2325 3335);
DISPLAY 0.617021 (2325 3335);
PAINT PINK (2325 3335);
FORCEPROP 2 LAST CDS_LIB mstr_standard
J 0
(2325 3325);
DISPLAY 0.787234 (2325 3325);
PAINT MONO (2325 3325);
DISPLAY INVISIBLE (2325 3325);
FORCEPROP 1 LAST BODY_TYPE PLUMBING
J 2
(2325 3275);
DISPLAY 1.234043 (2325 3275);
PAINT GREEN (2325 3275);
DISPLAY INVISIBLE (2325 3275);
FORCEPROP 1 LAST HDL_TAP TRUE
J 2
(2000 3200);
DISPLAY 1.234043 (2000 3200);
PAINT GREEN (2000 3200);
DISPLAY INVISIBLE (2000 3200);
FORCEPROP 1 LAST PATH I146
J 2
(2327 3325);
DISPLAY 0.872340 (2327 3325);
PAINT GREEN (2327 3325);
DISPLAY INVISIBLE (2327 3325);
FORCEADD TAP..6
R 2
(2325 3425);
FORCEPROP 3 LASTPIN (2275 3425) SIG_NAME M_L_DQS_DP<3>
J 0
(2285 3435);
DISPLAY 0.659574 (2285 3435);
PAINT MONO (2285 3435);
DISPLAY INVISIBLE (2285 3435);
FORCEPROP 1 LASTPIN (2275 3425) BN 3
J 2
(2325 3435);
DISPLAY 0.617021 (2325 3435);
PAINT PINK (2325 3435);
FORCEPROP 2 LAST CDS_LIB mstr_standard
J 0
(2325 3425);
DISPLAY 0.787234 (2325 3425);
PAINT MONO (2325 3425);
DISPLAY INVISIBLE (2325 3425);
FORCEPROP 1 LAST BODY_TYPE PLUMBING
J 2
(2325 3375);
DISPLAY 1.234043 (2325 3375);
PAINT GREEN (2325 3375);
DISPLAY INVISIBLE (2325 3375);
FORCEPROP 1 LAST HDL_TAP TRUE
J 2
(2000 3300);
DISPLAY 1.234043 (2000 3300);
PAINT GREEN (2000 3300);
DISPLAY INVISIBLE (2000 3300);
FORCEPROP 1 LAST PATH I147
J 2
(2327 3425);
DISPLAY 0.872340 (2327 3425);
PAINT GREEN (2327 3425);
DISPLAY INVISIBLE (2327 3425);
FORCEADD TAP..6
R 2
(2325 3625);
FORCEPROP 3 LASTPIN (2275 3625) SIG_NAME M_L_DQS_DP<5>
J 0
(2285 3635);
DISPLAY 0.659574 (2285 3635);
PAINT MONO (2285 3635);
DISPLAY INVISIBLE (2285 3635);
FORCEPROP 1 LASTPIN (2275 3625) BN 5
J 2
(2325 3635);
DISPLAY 0.617021 (2325 3635);
PAINT PINK (2325 3635);
FORCEPROP 2 LAST CDS_LIB mstr_standard
J 0
(2325 3625);
DISPLAY 0.787234 (2325 3625);
PAINT MONO (2325 3625);
DISPLAY INVISIBLE (2325 3625);
FORCEPROP 1 LAST BODY_TYPE PLUMBING
J 2
(2325 3575);
DISPLAY 1.234043 (2325 3575);
PAINT GREEN (2325 3575);
DISPLAY INVISIBLE (2325 3575);
FORCEPROP 1 LAST HDL_TAP TRUE
J 2
(2000 3500);
DISPLAY 1.234043 (2000 3500);
PAINT GREEN (2000 3500);
DISPLAY INVISIBLE (2000 3500);
FORCEPROP 1 LAST PATH I148
J 2
(2327 3625);
DISPLAY 0.872340 (2327 3625);
PAINT GREEN (2327 3625);
DISPLAY INVISIBLE (2327 3625);
FORCEADD TAP..6
R 2
(2325 3525);
FORCEPROP 3 LASTPIN (2275 3525) SIG_NAME M_L_DQS_DP<4>
J 0
(2285 3535);
DISPLAY 0.659574 (2285 3535);
PAINT MONO (2285 3535);
DISPLAY INVISIBLE (2285 3535);
FORCEPROP 1 LASTPIN (2275 3525) BN 4
J 2
(2325 3535);
DISPLAY 0.617021 (2325 3535);
PAINT PINK (2325 3535);
FORCEPROP 2 LAST CDS_LIB mstr_standard
J 0
(2325 3525);
DISPLAY 0.787234 (2325 3525);
PAINT MONO (2325 3525);
DISPLAY INVISIBLE (2325 3525);
FORCEPROP 1 LAST BODY_TYPE PLUMBING
J 2
(2325 3475);
DISPLAY 1.234043 (2325 3475);
PAINT GREEN (2325 3475);
DISPLAY INVISIBLE (2325 3475);
FORCEPROP 1 LAST HDL_TAP TRUE
J 2
(2000 3400);
DISPLAY 1.234043 (2000 3400);
PAINT GREEN (2000 3400);
DISPLAY INVISIBLE (2000 3400);
FORCEPROP 1 LAST PATH I149
J 2
(2327 3525);
DISPLAY 0.872340 (2327 3525);
PAINT GREEN (2327 3525);
DISPLAY INVISIBLE (2327 3525);
FORCEADD OFFPAGE..1
(-2225 2525);
FORCEPROP 2 LAST $XR0 61 
J 0
(-2476 2525);
DISPLAY 0.638298 (-2476 2525);
PAINT MONO (-2476 2525);
FORCEPROP 2 LAST $XR1 85 
J 0
(-2566 2525);
DISPLAY 0.638298 (-2566 2525);
PAINT MONO (-2566 2525);
FORCEPROP 2 LAST CDS_LIB mstr_standard
J 0
(-2225 2525);
DISPLAY 0.787234 (-2225 2525);
PAINT MONO (-2225 2525);
DISPLAY INVISIBLE (-2225 2525);
FORCEPROP 1 LAST OFFPAGE TRUE
J 0
(-1900 2400);
DISPLAY 0.936170 (-1900 2400);
PAINT GREEN (-1900 2400);
DISPLAY INVISIBLE (-1900 2400);
FORCEPROP 1 LAST COMMENT_BODY TRUE
J 0
(-2100 2425);
DISPLAY 0.936170 (-2100 2425);
PAINT GREEN (-2100 2425);
DISPLAY INVISIBLE (-2100 2425);
FORCEPROP 2 LAST PATH I15
J 0
(-2475 2575);
DISPLAY 1.021277 (-2475 2575);
PAINT ORANGE (-2475 2575);
DISPLAY INVISIBLE (-2475 2575);
FORCEADD TAP..6
R 2
(2325 3725);
FORCEPROP 3 LASTPIN (2275 3725) SIG_NAME M_L_DQS_DP<6>
J 0
(2285 3735);
DISPLAY 0.659574 (2285 3735);
PAINT MONO (2285 3735);
DISPLAY INVISIBLE (2285 3735);
FORCEPROP 1 LASTPIN (2275 3725) BN 6
J 2
(2325 3735);
DISPLAY 0.617021 (2325 3735);
PAINT PINK (2325 3735);
FORCEPROP 2 LAST CDS_LIB mstr_standard
J 0
(2325 3725);
DISPLAY 0.787234 (2325 3725);
PAINT MONO (2325 3725);
DISPLAY INVISIBLE (2325 3725);
FORCEPROP 1 LAST BODY_TYPE PLUMBING
J 2
(2325 3675);
DISPLAY 1.234043 (2325 3675);
PAINT GREEN (2325 3675);
DISPLAY INVISIBLE (2325 3675);
FORCEPROP 1 LAST HDL_TAP TRUE
J 2
(2000 3600);
DISPLAY 1.234043 (2000 3600);
PAINT GREEN (2000 3600);
DISPLAY INVISIBLE (2000 3600);
FORCEPROP 1 LAST PATH I150
J 2
(2327 3725);
DISPLAY 0.872340 (2327 3725);
PAINT GREEN (2327 3725);
DISPLAY INVISIBLE (2327 3725);
FORCEADD TAP..6
R 2
(2525 3475);
FORCEPROP 3 LASTPIN (2475 3475) SIG_NAME M_L_DQS_DN<4>
J 0
(2485 3485);
DISPLAY 0.659574 (2485 3485);
PAINT MONO (2485 3485);
DISPLAY INVISIBLE (2485 3485);
FORCEPROP 1 LASTPIN (2475 3475) BN 4
J 2
(2525 3485);
DISPLAY 0.617021 (2525 3485);
PAINT PINK (2525 3485);
FORCEPROP 2 LAST CDS_LIB mstr_standard
J 0
(2525 3475);
DISPLAY 0.787234 (2525 3475);
PAINT MONO (2525 3475);
DISPLAY INVISIBLE (2525 3475);
FORCEPROP 1 LAST BODY_TYPE PLUMBING
J 2
(2525 3425);
DISPLAY 1.234043 (2525 3425);
PAINT GREEN (2525 3425);
DISPLAY INVISIBLE (2525 3425);
FORCEPROP 1 LAST HDL_TAP TRUE
J 2
(2200 3350);
DISPLAY 1.234043 (2200 3350);
PAINT GREEN (2200 3350);
DISPLAY INVISIBLE (2200 3350);
FORCEPROP 1 LAST PATH I151
J 2
(2527 3475);
DISPLAY 0.872340 (2527 3475);
PAINT GREEN (2527 3475);
DISPLAY INVISIBLE (2527 3475);
FORCEADD TAP..6
R 2
(2525 3275);
FORCEPROP 3 LASTPIN (2475 3275) SIG_NAME M_L_DQS_DN<2>
J 0
(2485 3285);
DISPLAY 0.659574 (2485 3285);
PAINT MONO (2485 3285);
DISPLAY INVISIBLE (2485 3285);
FORCEPROP 1 LASTPIN (2475 3275) BN 2
J 2
(2525 3285);
DISPLAY 0.617021 (2525 3285);
PAINT PINK (2525 3285);
FORCEPROP 2 LAST CDS_LIB mstr_standard
J 0
(2525 3275);
DISPLAY 0.787234 (2525 3275);
PAINT MONO (2525 3275);
DISPLAY INVISIBLE (2525 3275);
FORCEPROP 1 LAST BODY_TYPE PLUMBING
J 2
(2525 3225);
DISPLAY 1.234043 (2525 3225);
PAINT GREEN (2525 3225);
DISPLAY INVISIBLE (2525 3225);
FORCEPROP 1 LAST HDL_TAP TRUE
J 2
(2200 3150);
DISPLAY 1.234043 (2200 3150);
PAINT GREEN (2200 3150);
DISPLAY INVISIBLE (2200 3150);
FORCEPROP 1 LAST PATH I152
J 2
(2527 3275);
DISPLAY 0.872340 (2527 3275);
PAINT GREEN (2527 3275);
DISPLAY INVISIBLE (2527 3275);
FORCEADD TAP..6
R 2
(2525 3375);
FORCEPROP 3 LASTPIN (2475 3375) SIG_NAME M_L_DQS_DN<3>
J 0
(2485 3385);
DISPLAY 0.659574 (2485 3385);
PAINT MONO (2485 3385);
DISPLAY INVISIBLE (2485 3385);
FORCEPROP 1 LASTPIN (2475 3375) BN 3
J 2
(2525 3385);
DISPLAY 0.617021 (2525 3385);
PAINT PINK (2525 3385);
FORCEPROP 2 LAST CDS_LIB mstr_standard
J 0
(2525 3375);
DISPLAY 0.787234 (2525 3375);
PAINT MONO (2525 3375);
DISPLAY INVISIBLE (2525 3375);
FORCEPROP 1 LAST BODY_TYPE PLUMBING
J 2
(2525 3325);
DISPLAY 1.234043 (2525 3325);
PAINT GREEN (2525 3325);
DISPLAY INVISIBLE (2525 3325);
FORCEPROP 1 LAST HDL_TAP TRUE
J 2
(2200 3250);
DISPLAY 1.234043 (2200 3250);
PAINT GREEN (2200 3250);
DISPLAY INVISIBLE (2200 3250);
FORCEPROP 1 LAST PATH I153
J 2
(2527 3375);
DISPLAY 0.872340 (2527 3375);
PAINT GREEN (2527 3375);
DISPLAY INVISIBLE (2527 3375);
FORCEADD TAP..6
R 2
(2525 3675);
FORCEPROP 3 LASTPIN (2475 3675) SIG_NAME M_L_DQS_DN<6>
J 0
(2485 3685);
DISPLAY 0.659574 (2485 3685);
PAINT MONO (2485 3685);
DISPLAY INVISIBLE (2485 3685);
FORCEPROP 1 LASTPIN (2475 3675) BN 6
J 2
(2525 3685);
DISPLAY 0.617021 (2525 3685);
PAINT PINK (2525 3685);
FORCEPROP 2 LAST CDS_LIB mstr_standard
J 0
(2525 3675);
DISPLAY 0.787234 (2525 3675);
PAINT MONO (2525 3675);
DISPLAY INVISIBLE (2525 3675);
FORCEPROP 1 LAST BODY_TYPE PLUMBING
J 2
(2525 3625);
DISPLAY 1.234043 (2525 3625);
PAINT GREEN (2525 3625);
DISPLAY INVISIBLE (2525 3625);
FORCEPROP 1 LAST HDL_TAP TRUE
J 2
(2200 3550);
DISPLAY 1.234043 (2200 3550);
PAINT GREEN (2200 3550);
DISPLAY INVISIBLE (2200 3550);
FORCEPROP 1 LAST PATH I154
J 2
(2527 3675);
DISPLAY 0.872340 (2527 3675);
PAINT GREEN (2527 3675);
DISPLAY INVISIBLE (2527 3675);
FORCEADD TAP..6
R 2
(2525 3575);
FORCEPROP 3 LASTPIN (2475 3575) SIG_NAME M_L_DQS_DN<5>
J 0
(2485 3585);
DISPLAY 0.659574 (2485 3585);
PAINT MONO (2485 3585);
DISPLAY INVISIBLE (2485 3585);
FORCEPROP 1 LASTPIN (2475 3575) BN 5
J 2
(2525 3585);
DISPLAY 0.617021 (2525 3585);
PAINT PINK (2525 3585);
FORCEPROP 2 LAST CDS_LIB mstr_standard
J 0
(2525 3575);
DISPLAY 0.787234 (2525 3575);
PAINT MONO (2525 3575);
DISPLAY INVISIBLE (2525 3575);
FORCEPROP 1 LAST BODY_TYPE PLUMBING
J 2
(2525 3525);
DISPLAY 1.234043 (2525 3525);
PAINT GREEN (2525 3525);
DISPLAY INVISIBLE (2525 3525);
FORCEPROP 1 LAST HDL_TAP TRUE
J 2
(2200 3450);
DISPLAY 1.234043 (2200 3450);
PAINT GREEN (2200 3450);
DISPLAY INVISIBLE (2200 3450);
FORCEPROP 1 LAST PATH I155
J 2
(2527 3575);
DISPLAY 0.872340 (2527 3575);
PAINT GREEN (2527 3575);
DISPLAY INVISIBLE (2527 3575);
FORCEADD GND..1
R 2
(4125 775);
FORCEPROP 3 LASTPIN (4125 825) SIG_NAME GND\g
J 0
(4135 835);
DISPLAY 0.659574 (4135 835);
PAINT MONO (4135 835);
DISPLAY INVISIBLE (4135 835);
FORCEPROP 1 LAST VOLTAGE 0
J 0
(4125 775);
PAINT SKYBLUE (4125 775);
DISPLAY INVISIBLE (4125 775);
FORCEPROP 1 LAST SIZE 1B
J 2
(4050 725);
DISPLAY 1.170213 (4050 725);
PAINT GREEN (4050 725);
DISPLAY INVISIBLE (4050 725);
FORCEPROP 2 LAST CDS_LIB mstr_symbols
J 0
(4125 775);
DISPLAY 0.787234 (4125 775);
PAINT MONO (4125 775);
DISPLAY INVISIBLE (4125 775);
FORCEPROP 2 LAST BOM_COST MEM
J 0
(4125 780);
PAINT ORANGE (4125 780);
DISPLAY INVISIBLE (4125 780);
FORCEPROP 1 LAST BODY_TYPE PLUMBING
J 2
(4170 732);
DISPLAY 0.340426 (4170 732);
PAINT GREEN (4170 732);
DISPLAY INVISIBLE (4170 732);
FORCEPROP 1 LAST PATH I156
J 2
(4050 775);
DISPLAY 0.872340 (4050 775);
PAINT AQUA (4050 775);
DISPLAY INVISIBLE (4050 775);
FORCEPROP 2 LAST ROOM DDR4_CH_D
J 0
(4125 780);
PAINT ORANGE (4125 780);
DISPLAY INVISIBLE (4125 780);
FORCEPROP 1 LAST HDL_POWER GND
J 2
(4125 925);
DISPLAY 0.553191 (4125 925);
PAINT GREEN (4125 925);
DISPLAY INVISIBLE (4125 925);
FORCEADD TAP..6
R 2
(2325 3825);
FORCEPROP 3 LASTPIN (2275 3825) SIG_NAME M_L_DQS_DP<7>
J 0
(2285 3835);
DISPLAY 0.659574 (2285 3835);
PAINT MONO (2285 3835);
DISPLAY INVISIBLE (2285 3835);
FORCEPROP 1 LASTPIN (2275 3825) BN 7
J 2
(2325 3835);
DISPLAY 0.617021 (2325 3835);
PAINT PINK (2325 3835);
FORCEPROP 2 LAST CDS_LIB mstr_standard
J 0
(2325 3825);
DISPLAY 0.787234 (2325 3825);
PAINT MONO (2325 3825);
DISPLAY INVISIBLE (2325 3825);
FORCEPROP 1 LAST BODY_TYPE PLUMBING
J 2
(2325 3775);
DISPLAY 1.234043 (2325 3775);
PAINT GREEN (2325 3775);
DISPLAY INVISIBLE (2325 3775);
FORCEPROP 1 LAST HDL_TAP TRUE
J 2
(2000 3700);
DISPLAY 1.234043 (2000 3700);
PAINT GREEN (2000 3700);
DISPLAY INVISIBLE (2000 3700);
FORCEPROP 1 LAST PATH I157
J 2
(2327 3825);
DISPLAY 0.872340 (2327 3825);
PAINT GREEN (2327 3825);
DISPLAY INVISIBLE (2327 3825);
FORCEADD TAP..6
R 2
(2325 4025);
FORCEPROP 3 LASTPIN (2275 4025) SIG_NAME M_L_DQS_DP<9>
J 0
(2285 4035);
DISPLAY 0.659574 (2285 4035);
PAINT MONO (2285 4035);
DISPLAY INVISIBLE (2285 4035);
FORCEPROP 1 LASTPIN (2275 4025) BN 9
J 2
(2325 4035);
DISPLAY 0.617021 (2325 4035);
PAINT PINK (2325 4035);
FORCEPROP 2 LAST CDS_LIB mstr_standard
J 0
(2325 4025);
DISPLAY 0.787234 (2325 4025);
PAINT MONO (2325 4025);
DISPLAY INVISIBLE (2325 4025);
FORCEPROP 1 LAST BODY_TYPE PLUMBING
J 2
(2325 3975);
DISPLAY 1.234043 (2325 3975);
PAINT GREEN (2325 3975);
DISPLAY INVISIBLE (2325 3975);
FORCEPROP 1 LAST HDL_TAP TRUE
J 2
(2000 3900);
DISPLAY 1.234043 (2000 3900);
PAINT GREEN (2000 3900);
DISPLAY INVISIBLE (2000 3900);
FORCEPROP 1 LAST PATH I158
J 2
(2327 4025);
DISPLAY 0.872340 (2327 4025);
PAINT GREEN (2327 4025);
DISPLAY INVISIBLE (2327 4025);
FORCEADD TAP..6
R 2
(2325 3925);
FORCEPROP 3 LASTPIN (2275 3925) SIG_NAME M_L_DQS_DP<8>
J 0
(2285 3935);
DISPLAY 0.659574 (2285 3935);
PAINT MONO (2285 3935);
DISPLAY INVISIBLE (2285 3935);
FORCEPROP 1 LASTPIN (2275 3925) BN 8
J 2
(2325 3935);
DISPLAY 0.617021 (2325 3935);
PAINT PINK (2325 3935);
FORCEPROP 2 LAST CDS_LIB mstr_standard
J 0
(2325 3925);
DISPLAY 0.787234 (2325 3925);
PAINT MONO (2325 3925);
DISPLAY INVISIBLE (2325 3925);
FORCEPROP 1 LAST BODY_TYPE PLUMBING
J 2
(2325 3875);
DISPLAY 1.234043 (2325 3875);
PAINT GREEN (2325 3875);
DISPLAY INVISIBLE (2325 3875);
FORCEPROP 1 LAST HDL_TAP TRUE
J 2
(2000 3800);
DISPLAY 1.234043 (2000 3800);
PAINT GREEN (2000 3800);
DISPLAY INVISIBLE (2000 3800);
FORCEPROP 1 LAST PATH I159
J 2
(2327 3925);
DISPLAY 0.872340 (2327 3925);
PAINT GREEN (2327 3925);
DISPLAY INVISIBLE (2327 3925);
FORCEADD OFFPAGE..1
(-2225 2725);
FORCEPROP 2 LAST $XR0 61 
J 0
(-2476 2725);
DISPLAY 0.638298 (-2476 2725);
PAINT MONO (-2476 2725);
FORCEPROP 2 LAST $XR1 85 
J 0
(-2566 2725);
DISPLAY 0.638298 (-2566 2725);
PAINT MONO (-2566 2725);
FORCEPROP 2 LAST CDS_LIB mstr_standard
J 0
(-2225 2725);
DISPLAY 0.787234 (-2225 2725);
PAINT MONO (-2225 2725);
DISPLAY INVISIBLE (-2225 2725);
FORCEPROP 1 LAST OFFPAGE TRUE
J 0
(-1900 2600);
DISPLAY 0.936170 (-1900 2600);
PAINT GREEN (-1900 2600);
DISPLAY INVISIBLE (-1900 2600);
FORCEPROP 1 LAST COMMENT_BODY TRUE
J 0
(-2100 2625);
DISPLAY 0.936170 (-2100 2625);
PAINT GREEN (-2100 2625);
DISPLAY INVISIBLE (-2100 2625);
FORCEPROP 2 LAST PATH I16
J 0
(-2475 2775);
DISPLAY 1.021277 (-2475 2775);
PAINT ORANGE (-2475 2775);
DISPLAY INVISIBLE (-2475 2775);
FORCEADD TAP..6
R 2
(2325 4125);
FORCEPROP 3 LASTPIN (2275 4125) SIG_NAME M_L_DQS_DP<10>
J 0
(2285 4135);
DISPLAY 0.659574 (2285 4135);
PAINT MONO (2285 4135);
DISPLAY INVISIBLE (2285 4135);
FORCEPROP 1 LASTPIN (2275 4125) BN 10
J 2
(2325 4135);
DISPLAY 0.617021 (2325 4135);
PAINT PINK (2325 4135);
FORCEPROP 2 LAST CDS_LIB mstr_standard
J 0
(2325 4125);
DISPLAY 0.787234 (2325 4125);
PAINT MONO (2325 4125);
DISPLAY INVISIBLE (2325 4125);
FORCEPROP 1 LAST BODY_TYPE PLUMBING
J 2
(2325 4075);
DISPLAY 1.234043 (2325 4075);
PAINT GREEN (2325 4075);
DISPLAY INVISIBLE (2325 4075);
FORCEPROP 1 LAST HDL_TAP TRUE
J 2
(2000 4000);
DISPLAY 1.234043 (2000 4000);
PAINT GREEN (2000 4000);
DISPLAY INVISIBLE (2000 4000);
FORCEPROP 1 LAST PATH I160
J 2
(2327 4125);
DISPLAY 0.872340 (2327 4125);
PAINT GREEN (2327 4125);
DISPLAY INVISIBLE (2327 4125);
FORCEADD TAP..6
R 2
(2325 4225);
FORCEPROP 3 LASTPIN (2275 4225) SIG_NAME M_L_DQS_DP<11>
J 0
(2285 4235);
DISPLAY 0.659574 (2285 4235);
PAINT MONO (2285 4235);
DISPLAY INVISIBLE (2285 4235);
FORCEPROP 1 LASTPIN (2275 4225) BN 11
J 2
(2325 4235);
DISPLAY 0.617021 (2325 4235);
PAINT PINK (2325 4235);
FORCEPROP 2 LAST CDS_LIB mstr_standard
J 0
(2325 4225);
DISPLAY 0.787234 (2325 4225);
PAINT MONO (2325 4225);
DISPLAY INVISIBLE (2325 4225);
FORCEPROP 1 LAST BODY_TYPE PLUMBING
J 2
(2325 4175);
DISPLAY 1.234043 (2325 4175);
PAINT GREEN (2325 4175);
DISPLAY INVISIBLE (2325 4175);
FORCEPROP 1 LAST HDL_TAP TRUE
J 2
(2000 4100);
DISPLAY 1.234043 (2000 4100);
PAINT GREEN (2000 4100);
DISPLAY INVISIBLE (2000 4100);
FORCEPROP 1 LAST PATH I161
J 2
(2327 4225);
DISPLAY 0.872340 (2327 4225);
PAINT GREEN (2327 4225);
DISPLAY INVISIBLE (2327 4225);
FORCEADD TAP..6
R 2
(2525 3975);
FORCEPROP 3 LASTPIN (2475 3975) SIG_NAME M_L_DQS_DN<9>
J 0
(2485 3985);
DISPLAY 0.659574 (2485 3985);
PAINT MONO (2485 3985);
DISPLAY INVISIBLE (2485 3985);
FORCEPROP 1 LASTPIN (2475 3975) BN 9
J 2
(2525 3985);
DISPLAY 0.617021 (2525 3985);
PAINT PINK (2525 3985);
FORCEPROP 2 LAST CDS_LIB mstr_standard
J 0
(2525 3975);
DISPLAY 0.787234 (2525 3975);
PAINT MONO (2525 3975);
DISPLAY INVISIBLE (2525 3975);
FORCEPROP 1 LAST BODY_TYPE PLUMBING
J 2
(2525 3925);
DISPLAY 1.234043 (2525 3925);
PAINT GREEN (2525 3925);
DISPLAY INVISIBLE (2525 3925);
FORCEPROP 1 LAST HDL_TAP TRUE
J 2
(2200 3850);
DISPLAY 1.234043 (2200 3850);
PAINT GREEN (2200 3850);
DISPLAY INVISIBLE (2200 3850);
FORCEPROP 1 LAST PATH I162
J 2
(2527 3975);
DISPLAY 0.872340 (2527 3975);
PAINT GREEN (2527 3975);
DISPLAY INVISIBLE (2527 3975);
FORCEADD TAP..6
R 2
(2525 3775);
FORCEPROP 3 LASTPIN (2475 3775) SIG_NAME M_L_DQS_DN<7>
J 0
(2485 3785);
DISPLAY 0.659574 (2485 3785);
PAINT MONO (2485 3785);
DISPLAY INVISIBLE (2485 3785);
FORCEPROP 1 LASTPIN (2475 3775) BN 7
J 2
(2525 3785);
DISPLAY 0.617021 (2525 3785);
PAINT PINK (2525 3785);
FORCEPROP 2 LAST CDS_LIB mstr_standard
J 0
(2525 3775);
DISPLAY 0.787234 (2525 3775);
PAINT MONO (2525 3775);
DISPLAY INVISIBLE (2525 3775);
FORCEPROP 1 LAST BODY_TYPE PLUMBING
J 2
(2525 3725);
DISPLAY 1.234043 (2525 3725);
PAINT GREEN (2525 3725);
DISPLAY INVISIBLE (2525 3725);
FORCEPROP 1 LAST HDL_TAP TRUE
J 2
(2200 3650);
DISPLAY 1.234043 (2200 3650);
PAINT GREEN (2200 3650);
DISPLAY INVISIBLE (2200 3650);
FORCEPROP 1 LAST PATH I163
J 2
(2527 3775);
DISPLAY 0.872340 (2527 3775);
PAINT GREEN (2527 3775);
DISPLAY INVISIBLE (2527 3775);
FORCEADD TAP..6
R 2
(2525 3875);
FORCEPROP 3 LASTPIN (2475 3875) SIG_NAME M_L_DQS_DN<8>
J 0
(2485 3885);
DISPLAY 0.659574 (2485 3885);
PAINT MONO (2485 3885);
DISPLAY INVISIBLE (2485 3885);
FORCEPROP 1 LASTPIN (2475 3875) BN 8
J 2
(2525 3885);
DISPLAY 0.617021 (2525 3885);
PAINT PINK (2525 3885);
FORCEPROP 2 LAST CDS_LIB mstr_standard
J 0
(2525 3875);
DISPLAY 0.787234 (2525 3875);
PAINT MONO (2525 3875);
DISPLAY INVISIBLE (2525 3875);
FORCEPROP 1 LAST BODY_TYPE PLUMBING
J 2
(2525 3825);
DISPLAY 1.234043 (2525 3825);
PAINT GREEN (2525 3825);
DISPLAY INVISIBLE (2525 3825);
FORCEPROP 1 LAST HDL_TAP TRUE
J 2
(2200 3750);
DISPLAY 1.234043 (2200 3750);
PAINT GREEN (2200 3750);
DISPLAY INVISIBLE (2200 3750);
FORCEPROP 1 LAST PATH I164
J 2
(2527 3875);
DISPLAY 0.872340 (2527 3875);
PAINT GREEN (2527 3875);
DISPLAY INVISIBLE (2527 3875);
FORCEADD TAP..6
R 2
(2525 4175);
FORCEPROP 3 LASTPIN (2475 4175) SIG_NAME M_L_DQS_DN<11>
J 0
(2485 4185);
DISPLAY 0.659574 (2485 4185);
PAINT MONO (2485 4185);
DISPLAY INVISIBLE (2485 4185);
FORCEPROP 1 LASTPIN (2475 4175) BN 11
J 2
(2525 4185);
DISPLAY 0.617021 (2525 4185);
PAINT PINK (2525 4185);
FORCEPROP 2 LAST CDS_LIB mstr_standard
J 0
(2525 4175);
DISPLAY 0.787234 (2525 4175);
PAINT MONO (2525 4175);
DISPLAY INVISIBLE (2525 4175);
FORCEPROP 1 LAST BODY_TYPE PLUMBING
J 2
(2525 4125);
DISPLAY 1.234043 (2525 4125);
PAINT GREEN (2525 4125);
DISPLAY INVISIBLE (2525 4125);
FORCEPROP 1 LAST HDL_TAP TRUE
J 2
(2200 4050);
DISPLAY 1.234043 (2200 4050);
PAINT GREEN (2200 4050);
DISPLAY INVISIBLE (2200 4050);
FORCEPROP 1 LAST PATH I165
J 2
(2527 4175);
DISPLAY 0.872340 (2527 4175);
PAINT GREEN (2527 4175);
DISPLAY INVISIBLE (2527 4175);
FORCEADD TAP..6
R 2
(2525 4075);
FORCEPROP 3 LASTPIN (2475 4075) SIG_NAME M_L_DQS_DN<10>
J 0
(2485 4085);
DISPLAY 0.659574 (2485 4085);
PAINT MONO (2485 4085);
DISPLAY INVISIBLE (2485 4085);
FORCEPROP 1 LASTPIN (2475 4075) BN 10
J 2
(2525 4085);
DISPLAY 0.617021 (2525 4085);
PAINT PINK (2525 4085);
FORCEPROP 2 LAST CDS_LIB mstr_standard
J 0
(2525 4075);
DISPLAY 0.787234 (2525 4075);
PAINT MONO (2525 4075);
DISPLAY INVISIBLE (2525 4075);
FORCEPROP 1 LAST BODY_TYPE PLUMBING
J 2
(2525 4025);
DISPLAY 1.234043 (2525 4025);
PAINT GREEN (2525 4025);
DISPLAY INVISIBLE (2525 4025);
FORCEPROP 1 LAST HDL_TAP TRUE
J 2
(2200 3950);
DISPLAY 1.234043 (2200 3950);
PAINT GREEN (2200 3950);
DISPLAY INVISIBLE (2200 3950);
FORCEPROP 1 LAST PATH I166
J 2
(2527 4075);
DISPLAY 0.872340 (2527 4075);
PAINT GREEN (2527 4075);
DISPLAY INVISIBLE (2527 4075);
FORCEADD TAP..6
R 2
(2525 4275);
FORCEPROP 3 LASTPIN (2475 4275) SIG_NAME M_L_DQS_DN<12>
J 0
(2485 4285);
DISPLAY 0.659574 (2485 4285);
PAINT MONO (2485 4285);
DISPLAY INVISIBLE (2485 4285);
FORCEPROP 1 LASTPIN (2475 4275) BN 12
J 2
(2525 4285);
DISPLAY 0.617021 (2525 4285);
PAINT PINK (2525 4285);
FORCEPROP 2 LAST CDS_LIB mstr_standard
J 0
(2525 4275);
DISPLAY 0.787234 (2525 4275);
PAINT MONO (2525 4275);
DISPLAY INVISIBLE (2525 4275);
FORCEPROP 1 LAST BODY_TYPE PLUMBING
J 2
(2525 4225);
DISPLAY 1.234043 (2525 4225);
PAINT GREEN (2525 4225);
DISPLAY INVISIBLE (2525 4225);
FORCEPROP 1 LAST HDL_TAP TRUE
J 2
(2200 4150);
DISPLAY 1.234043 (2200 4150);
PAINT GREEN (2200 4150);
DISPLAY INVISIBLE (2200 4150);
FORCEPROP 1 LAST PATH I167
J 2
(2527 4275);
DISPLAY 0.872340 (2527 4275);
PAINT GREEN (2527 4275);
DISPLAY INVISIBLE (2527 4275);
FORCEADD TAP..6
R 2
(2325 4325);
FORCEPROP 3 LASTPIN (2275 4325) SIG_NAME M_L_DQS_DP<12>
J 0
(2285 4335);
DISPLAY 0.659574 (2285 4335);
PAINT MONO (2285 4335);
DISPLAY INVISIBLE (2285 4335);
FORCEPROP 1 LASTPIN (2275 4325) BN 12
J 2
(2325 4335);
DISPLAY 0.617021 (2325 4335);
PAINT PINK (2325 4335);
FORCEPROP 2 LAST CDS_LIB mstr_standard
J 0
(2325 4325);
DISPLAY 0.787234 (2325 4325);
PAINT MONO (2325 4325);
DISPLAY INVISIBLE (2325 4325);
FORCEPROP 1 LAST BODY_TYPE PLUMBING
J 2
(2325 4275);
DISPLAY 1.234043 (2325 4275);
PAINT GREEN (2325 4275);
DISPLAY INVISIBLE (2325 4275);
FORCEPROP 1 LAST HDL_TAP TRUE
J 2
(2000 4200);
DISPLAY 1.234043 (2000 4200);
PAINT GREEN (2000 4200);
DISPLAY INVISIBLE (2000 4200);
FORCEPROP 1 LAST PATH I168
J 2
(2327 4325);
DISPLAY 0.872340 (2327 4325);
PAINT GREEN (2327 4325);
DISPLAY INVISIBLE (2327 4325);
FORCEADD TAP..6
R 2
(2325 4525);
FORCEPROP 3 LASTPIN (2275 4525) SIG_NAME M_L_DQS_DP<14>
J 0
(2285 4535);
DISPLAY 0.659574 (2285 4535);
PAINT MONO (2285 4535);
DISPLAY INVISIBLE (2285 4535);
FORCEPROP 1 LASTPIN (2275 4525) BN 14
J 2
(2325 4535);
DISPLAY 0.617021 (2325 4535);
PAINT PINK (2325 4535);
FORCEPROP 2 LAST CDS_LIB mstr_standard
J 0
(2325 4525);
DISPLAY 0.787234 (2325 4525);
PAINT MONO (2325 4525);
DISPLAY INVISIBLE (2325 4525);
FORCEPROP 1 LAST BODY_TYPE PLUMBING
J 2
(2325 4475);
DISPLAY 1.234043 (2325 4475);
PAINT GREEN (2325 4475);
DISPLAY INVISIBLE (2325 4475);
FORCEPROP 1 LAST HDL_TAP TRUE
J 2
(2000 4400);
DISPLAY 1.234043 (2000 4400);
PAINT GREEN (2000 4400);
DISPLAY INVISIBLE (2000 4400);
FORCEPROP 1 LAST PATH I169
J 2
(2327 4525);
DISPLAY 0.872340 (2327 4525);
PAINT GREEN (2327 4525);
DISPLAY INVISIBLE (2327 4525);
FORCEADD TAP..6
(-1625 2225);
FORCEPROP 3 LASTPIN (-1575 2225) SIG_NAME M_L_ECC<1>
J 0
(-1565 2235);
DISPLAY 0.659574 (-1565 2235);
PAINT MONO (-1565 2235);
DISPLAY INVISIBLE (-1565 2235);
FORCEPROP 1 LASTPIN (-1575 2225) BN 1
J 0
(-1625 2235);
DISPLAY 0.617021 (-1625 2235);
PAINT PINK (-1625 2235);
FORCEPROP 2 LAST CDS_LIB mstr_standard
J 0
(-1625 2225);
DISPLAY 0.787234 (-1625 2225);
PAINT MONO (-1625 2225);
DISPLAY INVISIBLE (-1625 2225);
FORCEPROP 1 LAST BODY_TYPE PLUMBING
J 0
(-1625 2175);
DISPLAY 1.234043 (-1625 2175);
PAINT GREEN (-1625 2175);
DISPLAY INVISIBLE (-1625 2175);
FORCEPROP 1 LAST HDL_TAP TRUE
J 0
(-1300 2100);
DISPLAY 1.234043 (-1300 2100);
PAINT GREEN (-1300 2100);
DISPLAY INVISIBLE (-1300 2100);
FORCEPROP 1 LAST PATH I17
J 0
(-1627 2225);
DISPLAY 0.872340 (-1627 2225);
PAINT GREEN (-1627 2225);
DISPLAY INVISIBLE (-1627 2225);
FORCEADD TAP..6
R 2
(2325 4425);
FORCEPROP 3 LASTPIN (2275 4425) SIG_NAME M_L_DQS_DP<13>
J 0
(2285 4435);
DISPLAY 0.659574 (2285 4435);
PAINT MONO (2285 4435);
DISPLAY INVISIBLE (2285 4435);
FORCEPROP 1 LASTPIN (2275 4425) BN 13
J 2
(2325 4435);
DISPLAY 0.617021 (2325 4435);
PAINT PINK (2325 4435);
FORCEPROP 2 LAST CDS_LIB mstr_standard
J 0
(2325 4425);
DISPLAY 0.787234 (2325 4425);
PAINT MONO (2325 4425);
DISPLAY INVISIBLE (2325 4425);
FORCEPROP 1 LAST BODY_TYPE PLUMBING
J 2
(2325 4375);
DISPLAY 1.234043 (2325 4375);
PAINT GREEN (2325 4375);
DISPLAY INVISIBLE (2325 4375);
FORCEPROP 1 LAST HDL_TAP TRUE
J 2
(2000 4300);
DISPLAY 1.234043 (2000 4300);
PAINT GREEN (2000 4300);
DISPLAY INVISIBLE (2000 4300);
FORCEPROP 1 LAST PATH I170
J 2
(2327 4425);
DISPLAY 0.872340 (2327 4425);
PAINT GREEN (2327 4425);
DISPLAY INVISIBLE (2327 4425);
FORCEADD TAP..6
R 2
(2325 4625);
FORCEPROP 3 LASTPIN (2275 4625) SIG_NAME M_L_DQS_DP<15>
J 0
(2285 4635);
DISPLAY 0.659574 (2285 4635);
PAINT MONO (2285 4635);
DISPLAY INVISIBLE (2285 4635);
FORCEPROP 1 LASTPIN (2275 4625) BN 15
J 2
(2325 4635);
DISPLAY 0.617021 (2325 4635);
PAINT PINK (2325 4635);
FORCEPROP 2 LAST CDS_LIB mstr_standard
J 0
(2325 4625);
DISPLAY 0.787234 (2325 4625);
PAINT MONO (2325 4625);
DISPLAY INVISIBLE (2325 4625);
FORCEPROP 1 LAST BODY_TYPE PLUMBING
J 2
(2325 4575);
DISPLAY 1.234043 (2325 4575);
PAINT GREEN (2325 4575);
DISPLAY INVISIBLE (2325 4575);
FORCEPROP 1 LAST HDL_TAP TRUE
J 2
(2000 4500);
DISPLAY 1.234043 (2000 4500);
PAINT GREEN (2000 4500);
DISPLAY INVISIBLE (2000 4500);
FORCEPROP 1 LAST PATH I171
J 2
(2327 4625);
DISPLAY 0.872340 (2327 4625);
PAINT GREEN (2327 4625);
DISPLAY INVISIBLE (2327 4625);
FORCEADD TAP..6
R 2
(2325 4725);
FORCEPROP 3 LASTPIN (2275 4725) SIG_NAME M_L_DQS_DP<16>
J 0
(2285 4735);
DISPLAY 0.659574 (2285 4735);
PAINT MONO (2285 4735);
DISPLAY INVISIBLE (2285 4735);
FORCEPROP 1 LASTPIN (2275 4725) BN 16
J 2
(2325 4735);
DISPLAY 0.617021 (2325 4735);
PAINT PINK (2325 4735);
FORCEPROP 2 LAST CDS_LIB mstr_standard
J 0
(2325 4725);
DISPLAY 0.787234 (2325 4725);
PAINT MONO (2325 4725);
DISPLAY INVISIBLE (2325 4725);
FORCEPROP 1 LAST BODY_TYPE PLUMBING
J 2
(2325 4675);
DISPLAY 1.234043 (2325 4675);
PAINT GREEN (2325 4675);
DISPLAY INVISIBLE (2325 4675);
FORCEPROP 1 LAST HDL_TAP TRUE
J 2
(2000 4600);
DISPLAY 1.234043 (2000 4600);
PAINT GREEN (2000 4600);
DISPLAY INVISIBLE (2000 4600);
FORCEPROP 1 LAST PATH I172
J 2
(2327 4725);
DISPLAY 0.872340 (2327 4725);
PAINT GREEN (2327 4725);
DISPLAY INVISIBLE (2327 4725);
FORCEADD TAP..6
R 2
(2525 4375);
FORCEPROP 3 LASTPIN (2475 4375) SIG_NAME M_L_DQS_DN<13>
J 0
(2485 4385);
DISPLAY 0.659574 (2485 4385);
PAINT MONO (2485 4385);
DISPLAY INVISIBLE (2485 4385);
FORCEPROP 1 LASTPIN (2475 4375) BN 13
J 2
(2525 4385);
DISPLAY 0.617021 (2525 4385);
PAINT PINK (2525 4385);
FORCEPROP 2 LAST CDS_LIB mstr_standard
J 0
(2525 4375);
DISPLAY 0.787234 (2525 4375);
PAINT MONO (2525 4375);
DISPLAY INVISIBLE (2525 4375);
FORCEPROP 1 LAST BODY_TYPE PLUMBING
J 2
(2525 4325);
DISPLAY 1.234043 (2525 4325);
PAINT GREEN (2525 4325);
DISPLAY INVISIBLE (2525 4325);
FORCEPROP 1 LAST HDL_TAP TRUE
J 2
(2200 4250);
DISPLAY 1.234043 (2200 4250);
PAINT GREEN (2200 4250);
DISPLAY INVISIBLE (2200 4250);
FORCEPROP 1 LAST PATH I173
J 2
(2527 4375);
DISPLAY 0.872340 (2527 4375);
PAINT GREEN (2527 4375);
DISPLAY INVISIBLE (2527 4375);
FORCEADD TAP..6
R 2
(2525 4475);
FORCEPROP 3 LASTPIN (2475 4475) SIG_NAME M_L_DQS_DN<14>
J 0
(2485 4485);
DISPLAY 0.659574 (2485 4485);
PAINT MONO (2485 4485);
DISPLAY INVISIBLE (2485 4485);
FORCEPROP 1 LASTPIN (2475 4475) BN 14
J 2
(2525 4485);
DISPLAY 0.617021 (2525 4485);
PAINT PINK (2525 4485);
FORCEPROP 2 LAST CDS_LIB mstr_standard
J 0
(2525 4475);
DISPLAY 0.787234 (2525 4475);
PAINT MONO (2525 4475);
DISPLAY INVISIBLE (2525 4475);
FORCEPROP 1 LAST BODY_TYPE PLUMBING
J 2
(2525 4425);
DISPLAY 1.234043 (2525 4425);
PAINT GREEN (2525 4425);
DISPLAY INVISIBLE (2525 4425);
FORCEPROP 1 LAST HDL_TAP TRUE
J 2
(2200 4350);
DISPLAY 1.234043 (2200 4350);
PAINT GREEN (2200 4350);
DISPLAY INVISIBLE (2200 4350);
FORCEPROP 1 LAST PATH I174
J 2
(2527 4475);
DISPLAY 0.872340 (2527 4475);
PAINT GREEN (2527 4475);
DISPLAY INVISIBLE (2527 4475);
FORCEADD TAP..6
R 2
(2525 4775);
FORCEPROP 3 LASTPIN (2475 4775) SIG_NAME M_L_DQS_DN<17>
J 0
(2485 4785);
DISPLAY 0.659574 (2485 4785);
PAINT MONO (2485 4785);
DISPLAY INVISIBLE (2485 4785);
FORCEPROP 1 LASTPIN (2475 4775) BN 17
J 2
(2525 4785);
DISPLAY 0.617021 (2525 4785);
PAINT PINK (2525 4785);
FORCEPROP 2 LAST CDS_LIB mstr_standard
J 2
(2525 4775);
DISPLAY 0.787234 (2525 4775);
PAINT MONO (2525 4775);
DISPLAY INVISIBLE (2525 4775);
FORCEPROP 1 LAST BODY_TYPE PLUMBING
J 2
(2525 4725);
DISPLAY 1.234043 (2525 4725);
PAINT GREEN (2525 4725);
DISPLAY INVISIBLE (2525 4725);
FORCEPROP 1 LAST HDL_TAP TRUE
J 2
(2200 4650);
DISPLAY 1.234043 (2200 4650);
PAINT GREEN (2200 4650);
DISPLAY INVISIBLE (2200 4650);
FORCEPROP 1 LAST PATH I175
J 2
(2527 4775);
DISPLAY 0.872340 (2527 4775);
PAINT GREEN (2527 4775);
DISPLAY INVISIBLE (2527 4775);
FORCEADD TAP..6
R 2
(2525 4675);
FORCEPROP 3 LASTPIN (2475 4675) SIG_NAME M_L_DQS_DN<16>
J 0
(2485 4685);
DISPLAY 0.659574 (2485 4685);
PAINT MONO (2485 4685);
DISPLAY INVISIBLE (2485 4685);
FORCEPROP 1 LASTPIN (2475 4675) BN 16
J 2
(2525 4685);
DISPLAY 0.617021 (2525 4685);
PAINT PINK (2525 4685);
FORCEPROP 2 LAST CDS_LIB mstr_standard
J 0
(2525 4675);
DISPLAY 0.787234 (2525 4675);
PAINT MONO (2525 4675);
DISPLAY INVISIBLE (2525 4675);
FORCEPROP 1 LAST BODY_TYPE PLUMBING
J 2
(2525 4625);
DISPLAY 1.234043 (2525 4625);
PAINT GREEN (2525 4625);
DISPLAY INVISIBLE (2525 4625);
FORCEPROP 1 LAST HDL_TAP TRUE
J 2
(2200 4550);
DISPLAY 1.234043 (2200 4550);
PAINT GREEN (2200 4550);
DISPLAY INVISIBLE (2200 4550);
FORCEPROP 1 LAST PATH I176
J 2
(2527 4675);
DISPLAY 0.872340 (2527 4675);
PAINT GREEN (2527 4675);
DISPLAY INVISIBLE (2527 4675);
FORCEADD TAP..6
R 2
(2525 4575);
FORCEPROP 3 LASTPIN (2475 4575) SIG_NAME M_L_DQS_DN<15>
J 0
(2485 4585);
DISPLAY 0.659574 (2485 4585);
PAINT MONO (2485 4585);
DISPLAY INVISIBLE (2485 4585);
FORCEPROP 1 LASTPIN (2475 4575) BN 15
J 2
(2525 4585);
DISPLAY 0.617021 (2525 4585);
PAINT PINK (2525 4585);
FORCEPROP 2 LAST CDS_LIB mstr_standard
J 0
(2525 4575);
DISPLAY 0.787234 (2525 4575);
PAINT MONO (2525 4575);
DISPLAY INVISIBLE (2525 4575);
FORCEPROP 1 LAST BODY_TYPE PLUMBING
J 2
(2525 4525);
DISPLAY 1.234043 (2525 4525);
PAINT GREEN (2525 4525);
DISPLAY INVISIBLE (2525 4525);
FORCEPROP 1 LAST HDL_TAP TRUE
J 2
(2200 4450);
DISPLAY 1.234043 (2200 4450);
PAINT GREEN (2200 4450);
DISPLAY INVISIBLE (2200 4450);
FORCEPROP 1 LAST PATH I177
J 2
(2527 4575);
DISPLAY 0.872340 (2527 4575);
PAINT GREEN (2527 4575);
DISPLAY INVISIBLE (2527 4575);
FORCEADD TAP..6
R 2
(2325 4825);
FORCEPROP 3 LASTPIN (2275 4825) SIG_NAME M_L_DQS_DP<17>
J 0
(2285 4835);
DISPLAY 0.659574 (2285 4835);
PAINT MONO (2285 4835);
DISPLAY INVISIBLE (2285 4835);
FORCEPROP 1 LASTPIN (2275 4825) BN 17
J 2
(2325 4835);
DISPLAY 0.617021 (2325 4835);
PAINT PINK (2325 4835);
FORCEPROP 2 LAST CDS_LIB mstr_standard
J 2
(2325 4825);
DISPLAY 0.787234 (2325 4825);
PAINT MONO (2325 4825);
DISPLAY INVISIBLE (2325 4825);
FORCEPROP 1 LAST BODY_TYPE PLUMBING
J 2
(2325 4775);
DISPLAY 1.234043 (2325 4775);
PAINT GREEN (2325 4775);
DISPLAY INVISIBLE (2325 4775);
FORCEPROP 1 LAST HDL_TAP TRUE
J 2
(2000 4700);
DISPLAY 1.234043 (2000 4700);
PAINT GREEN (2000 4700);
DISPLAY INVISIBLE (2000 4700);
FORCEPROP 1 LAST PATH I178
J 2
(2327 4825);
DISPLAY 0.872340 (2327 4825);
PAINT GREEN (2327 4825);
DISPLAY INVISIBLE (2327 4825);
FORCEADD OFFPAGE..3
(3225 4825);
FORCEPROP 2 LAST $XR0 61 
J 0
(3439 4825);
DISPLAY 0.638298 (3439 4825);
PAINT MONO (3439 4825);
FORCEPROP 2 LAST $XR1 85 
J 0
(3529 4825);
DISPLAY 0.638298 (3529 4825);
PAINT MONO (3529 4825);
FORCEPROP 2 LAST CDS_LIB mstr_standard
J 0
(3225 4825);
DISPLAY 0.787234 (3225 4825);
PAINT MONO (3225 4825);
DISPLAY INVISIBLE (3225 4825);
FORCEPROP 1 LAST OFFPAGE TRUE
J 0
(3550 4700);
DISPLAY 0.936170 (3550 4700);
PAINT GREEN (3550 4700);
DISPLAY INVISIBLE (3550 4700);
FORCEPROP 1 LAST COMMENT_BODY TRUE
J 0
(3175 4725);
DISPLAY 0.936170 (3175 4725);
PAINT GREEN (3175 4725);
DISPLAY INVISIBLE (3175 4725);
FORCEPROP 2 LAST PATH I179
J 0
(3450 4875);
DISPLAY 1.021277 (3450 4875);
PAINT ORANGE (3450 4875);
DISPLAY INVISIBLE (3450 4875);
FORCEADD TAP..6
(-1625 2175);
FORCEPROP 3 LASTPIN (-1575 2175) SIG_NAME M_L_ECC<0>
J 0
(-1565 2185);
DISPLAY 0.659574 (-1565 2185);
PAINT MONO (-1565 2185);
DISPLAY INVISIBLE (-1565 2185);
FORCEPROP 1 LASTPIN (-1575 2175) BN 0
J 0
(-1625 2185);
DISPLAY 0.617021 (-1625 2185);
PAINT PINK (-1625 2185);
FORCEPROP 2 LAST CDS_LIB mstr_standard
J 0
(-1625 2175);
DISPLAY 0.787234 (-1625 2175);
PAINT MONO (-1625 2175);
DISPLAY INVISIBLE (-1625 2175);
FORCEPROP 1 LAST BODY_TYPE PLUMBING
J 0
(-1625 2125);
DISPLAY 1.234043 (-1625 2125);
PAINT GREEN (-1625 2125);
DISPLAY INVISIBLE (-1625 2125);
FORCEPROP 1 LAST HDL_TAP TRUE
J 0
(-1300 2050);
DISPLAY 1.234043 (-1300 2050);
PAINT GREEN (-1300 2050);
DISPLAY INVISIBLE (-1300 2050);
FORCEPROP 1 LAST PATH I18
J 0
(-1627 2175);
DISPLAY 0.872340 (-1627 2175);
PAINT GREEN (-1627 2175);
DISPLAY INVISIBLE (-1627 2175);
FORCEADD OFFPAGE..3
(3225 4875);
FORCEPROP 2 LAST $XR0 61 
J 0
(3439 4875);
DISPLAY 0.638298 (3439 4875);
PAINT MONO (3439 4875);
FORCEPROP 2 LAST $XR1 85 
J 0
(3529 4875);
DISPLAY 0.638298 (3529 4875);
PAINT MONO (3529 4875);
FORCEPROP 2 LAST CDS_LIB mstr_standard
J 0
(3225 4875);
DISPLAY 0.787234 (3225 4875);
PAINT MONO (3225 4875);
DISPLAY INVISIBLE (3225 4875);
FORCEPROP 1 LAST OFFPAGE TRUE
J 0
(3550 4750);
DISPLAY 0.936170 (3550 4750);
PAINT GREEN (3550 4750);
DISPLAY INVISIBLE (3550 4750);
FORCEPROP 1 LAST COMMENT_BODY TRUE
J 0
(3175 4775);
DISPLAY 0.936170 (3175 4775);
PAINT GREEN (3175 4775);
DISPLAY INVISIBLE (3175 4775);
FORCEPROP 2 LAST PATH I180
J 0
(3450 4925);
DISPLAY 1.021277 (3450 4925);
PAINT ORANGE (3450 4925);
DISPLAY INVISIBLE (3450 4925);
FORCEADD P12V_NVDIMM_KLM..1
(2000 2700);
FORCEPROP 3 LASTPIN (2000 2650) SIG_NAME P12V_NVDIMM_KLM\g
J 0
(2010 2660);
DISPLAY 0.659574 (2010 2660);
PAINT MONO (2010 2660);
DISPLAY INVISIBLE (2010 2660);
FORCEPROP 1 LAST VOLTAGE 12.0
J 0
(1955 2657);
DISPLAY 0.340426 (1955 2657);
PAINT SKYBLUE (1955 2657);
DISPLAY INVISIBLE (1955 2657);
FORCEPROP 2 LAST CDS_LIB mstr_symbols
J 0
(2000 2700);
PAINT ORANGE (2000 2700);
DISPLAY INVISIBLE (2000 2700);
FORCEPROP 1 LAST BODY_TYPE PLUMBING
J 0
(1955 2657);
DISPLAY 0.340426 (1955 2657);
PAINT GREEN (1955 2657);
DISPLAY INVISIBLE (1955 2657);
FORCEPROP 1 LAST PATH I181
J 0
(2050 2725);
DISPLAY 0.872340 (2050 2725);
PAINT AQUA (2050 2725);
DISPLAY INVISIBLE (2050 2725);
FORCEPROP 1 LAST HDL_POWER P12V_NVDIMM_KLM
J 1
(2000 2750);
DISPLAY 0.872340 (2000 2750);
PAINT GREEN (2000 2750);
DISPLAY INVISIBLE (2000 2750);
FORCEADD CAP_A..1
R 2
(-3025 1225);
FORCEPROP 1 LAST LOCATION C1A17
J 2
(-3075 1325);
DISPLAY 0.617021 (-3075 1325);
PAINT AQUA (-3075 1325);
FORCEPROP 1 LAST PART_NUMBER A36096-045
J 2
(-3075 1075);
DISPLAY 0.617021 (-3075 1075);
PAINT BLUE (-3075 1075);
FORCEPROP 1 LAST VALUE 0.01UF
J 2
(-3075 1275);
DISPLAY 0.617021 (-3075 1275);
PAINT SKYBLUE (-3075 1275);
FORCEPROP 1 LAST TOLERANCE 10%
J 2
(-3075 1175);
DISPLAY 0.617021 (-3075 1175);
PAINT SKYBLUE (-3075 1175);
FORCEPROP 1 LAST PACK_TYPE 0402V
J 2
(-3075 1025);
DISPLAY 0.617021 (-3075 1025);
PAINT SKYBLUE (-3075 1025);
FORCEPROP 1 LAST VOLTAGE 25V
J 2
(-3075 1225);
DISPLAY 0.617021 (-3075 1225);
PAINT SKYBLUE (-3075 1225);
FORCEPROP 1 LAST MATERIAL X7R
J 2
(-3075 1125);
DISPLAY 0.617021 (-3075 1125);
PAINT SKYBLUE (-3075 1125);
FORCEPROP 2 LAST CDS_LOCATION C1A17
J 2
(-3075 1325);
DISPLAY 0.617021 (-3075 1325);
PAINT AQUA (-3075 1325);
DISPLAY INVISIBLE (-3075 1325);
FORCEPROP 0 LAST BOM_COST MEM
J 2
(-3075 1425);
DISPLAY 1.021277 (-3075 1425);
PAINT ORANGE (-3075 1425);
DISPLAY INVISIBLE (-3075 1425);
FORCEPROP 2 LAST CDS_LIB dev_discrete
J 0
(-3025 1225);
PAINT ORANGE (-3025 1225);
DISPLAY INVISIBLE (-3025 1225);
FORCEPROP 2 LAST CDS_SEC 1
J 0
(-3075 1425);
DISPLAY 1.021277 (-3075 1425);
PAINT ORANGE (-3075 1425);
DISPLAY INVISIBLE (-3075 1425);
FORCEPROP 2 LAST $SEC 1
J 0
(-3075 1425);
DISPLAY 0.680851 (-3075 1425);
PAINT MONO (-3075 1425);
DISPLAY INVISIBLE (-3075 1425);
FORCEPROP 1 LAST PATH I182
J 2
(-3075 1375);
DISPLAY 0.978723 (-3075 1375);
PAINT WHITE (-3075 1375);
DISPLAY INVISIBLE (-3075 1375);
FORCEPROP 0 LAST ROOM DDR4_CH_D
J 2
(-3075 1425);
DISPLAY 1.021277 (-3075 1425);
PAINT ORANGE (-3075 1425);
DISPLAY INVISIBLE (-3075 1425);
FORCEPROP 1 LASTPIN (-3025 1325) $PN 1
J 2
(-3035 1305);
DISPLAY 0.787234 (-3035 1305);
PAINT ORANGE (-3035 1305);
DISPLAY INVISIBLE (-3035 1305);
FORCEPROP 1 LASTPIN (-3025 1125) $PN 2
J 2
(-3035 1105);
DISPLAY 0.787234 (-3035 1105);
PAINT ORANGE (-3035 1105);
DISPLAY INVISIBLE (-3035 1105);
FORCEADD TAP..6
(-1625 2325);
FORCEPROP 3 LASTPIN (-1575 2325) SIG_NAME M_L_ECC<3>
J 0
(-1565 2335);
DISPLAY 0.659574 (-1565 2335);
PAINT MONO (-1565 2335);
DISPLAY INVISIBLE (-1565 2335);
FORCEPROP 1 LASTPIN (-1575 2325) BN 3
J 0
(-1625 2335);
DISPLAY 0.617021 (-1625 2335);
PAINT PINK (-1625 2335);
FORCEPROP 2 LAST CDS_LIB mstr_standard
J 0
(-1625 2325);
DISPLAY 0.787234 (-1625 2325);
PAINT MONO (-1625 2325);
DISPLAY INVISIBLE (-1625 2325);
FORCEPROP 1 LAST BODY_TYPE PLUMBING
J 0
(-1625 2275);
DISPLAY 1.234043 (-1625 2275);
PAINT GREEN (-1625 2275);
DISPLAY INVISIBLE (-1625 2275);
FORCEPROP 1 LAST HDL_TAP TRUE
J 0
(-1300 2200);
DISPLAY 1.234043 (-1300 2200);
PAINT GREEN (-1300 2200);
DISPLAY INVISIBLE (-1300 2200);
FORCEPROP 1 LAST PATH I19
J 0
(-1627 2325);
DISPLAY 0.872340 (-1627 2325);
PAINT GREEN (-1627 2325);
DISPLAY INVISIBLE (-1627 2325);
FORCEADD GND..1
(-3025 975);
FORCEPROP 3 LASTPIN (-3025 1025) SIG_NAME GND\g
J 0
(-3015 1035);
DISPLAY 0.659574 (-3015 1035);
PAINT MONO (-3015 1035);
DISPLAY INVISIBLE (-3015 1035);
FORCEPROP 1 LAST VOLTAGE 0
J 0
(-3025 975);
PAINT SKYBLUE (-3025 975);
DISPLAY INVISIBLE (-3025 975);
FORCEPROP 1 LAST SIZE 1B
J 0
(-2950 925);
DISPLAY 1.787234 (-2950 925);
PAINT GREEN (-2950 925);
DISPLAY INVISIBLE (-2950 925);
FORCEPROP 2 LAST CDS_LIB mstr_symbols
J 0
(-3025 975);
PAINT ORANGE (-3025 975);
DISPLAY INVISIBLE (-3025 975);
FORCEPROP 2 LAST BOM_COST MEM
J 0
(-3025 980);
PAINT ORANGE (-3025 980);
DISPLAY INVISIBLE (-3025 980);
FORCEPROP 1 LAST BODY_TYPE PLUMBING
J 0
(-3070 932);
DISPLAY 0.340426 (-3070 932);
PAINT GREEN (-3070 932);
DISPLAY INVISIBLE (-3070 932);
FORCEPROP 1 LAST PATH I2
J 0
(-2950 975);
DISPLAY 0.872340 (-2950 975);
PAINT AQUA (-2950 975);
DISPLAY INVISIBLE (-2950 975);
FORCEPROP 2 LAST ROOM DDR4_CH_D
J 0
(-3025 980);
PAINT ORANGE (-3025 980);
DISPLAY INVISIBLE (-3025 980);
FORCEPROP 1 LAST HDL_POWER GND
J 0
(-3025 1125);
DISPLAY 1.404255 (-3025 1125);
PAINT GREEN (-3025 1125);
DISPLAY INVISIBLE (-3025 1125);
FORCEADD TAP..6
(-1625 2275);
FORCEPROP 3 LASTPIN (-1575 2275) SIG_NAME M_L_ECC<2>
J 0
(-1565 2285);
DISPLAY 0.659574 (-1565 2285);
PAINT MONO (-1565 2285);
DISPLAY INVISIBLE (-1565 2285);
FORCEPROP 1 LASTPIN (-1575 2275) BN 2
J 0
(-1625 2285);
DISPLAY 0.617021 (-1625 2285);
PAINT PINK (-1625 2285);
FORCEPROP 2 LAST CDS_LIB mstr_standard
J 0
(-1625 2275);
DISPLAY 0.787234 (-1625 2275);
PAINT MONO (-1625 2275);
DISPLAY INVISIBLE (-1625 2275);
FORCEPROP 1 LAST BODY_TYPE PLUMBING
J 0
(-1625 2225);
DISPLAY 1.234043 (-1625 2225);
PAINT GREEN (-1625 2225);
DISPLAY INVISIBLE (-1625 2225);
FORCEPROP 1 LAST HDL_TAP TRUE
J 0
(-1300 2150);
DISPLAY 1.234043 (-1300 2150);
PAINT GREEN (-1300 2150);
DISPLAY INVISIBLE (-1300 2150);
FORCEPROP 1 LAST PATH I20
J 0
(-1627 2275);
DISPLAY 0.872340 (-1627 2275);
PAINT GREEN (-1627 2275);
DISPLAY INVISIBLE (-1627 2275);
FORCEADD TAP..6
(-1625 2375);
FORCEPROP 3 LASTPIN (-1575 2375) SIG_NAME M_L_ECC<4>
J 0
(-1565 2385);
DISPLAY 0.659574 (-1565 2385);
PAINT MONO (-1565 2385);
DISPLAY INVISIBLE (-1565 2385);
FORCEPROP 1 LASTPIN (-1575 2375) BN 4
J 0
(-1625 2385);
DISPLAY 0.617021 (-1625 2385);
PAINT PINK (-1625 2385);
FORCEPROP 2 LAST CDS_LIB mstr_standard
J 0
(-1625 2375);
DISPLAY 0.787234 (-1625 2375);
PAINT MONO (-1625 2375);
DISPLAY INVISIBLE (-1625 2375);
FORCEPROP 1 LAST BODY_TYPE PLUMBING
J 0
(-1625 2325);
DISPLAY 1.234043 (-1625 2325);
PAINT GREEN (-1625 2325);
DISPLAY INVISIBLE (-1625 2325);
FORCEPROP 1 LAST HDL_TAP TRUE
J 0
(-1300 2250);
DISPLAY 1.234043 (-1300 2250);
PAINT GREEN (-1300 2250);
DISPLAY INVISIBLE (-1300 2250);
FORCEPROP 1 LAST PATH I21
J 0
(-1627 2375);
DISPLAY 0.872340 (-1627 2375);
PAINT GREEN (-1627 2375);
DISPLAY INVISIBLE (-1627 2375);
FORCEADD TAP..6
(-1625 2425);
FORCEPROP 3 LASTPIN (-1575 2425) SIG_NAME M_L_ECC<5>
J 0
(-1565 2435);
DISPLAY 0.659574 (-1565 2435);
PAINT MONO (-1565 2435);
DISPLAY INVISIBLE (-1565 2435);
FORCEPROP 1 LASTPIN (-1575 2425) BN 5
J 0
(-1625 2435);
DISPLAY 0.617021 (-1625 2435);
PAINT PINK (-1625 2435);
FORCEPROP 2 LAST CDS_LIB mstr_standard
J 0
(-1625 2425);
DISPLAY 0.787234 (-1625 2425);
PAINT MONO (-1625 2425);
DISPLAY INVISIBLE (-1625 2425);
FORCEPROP 1 LAST BODY_TYPE PLUMBING
J 0
(-1625 2375);
DISPLAY 1.234043 (-1625 2375);
PAINT GREEN (-1625 2375);
DISPLAY INVISIBLE (-1625 2375);
FORCEPROP 1 LAST HDL_TAP TRUE
J 0
(-1300 2300);
DISPLAY 1.234043 (-1300 2300);
PAINT GREEN (-1300 2300);
DISPLAY INVISIBLE (-1300 2300);
FORCEPROP 1 LAST PATH I22
J 0
(-1627 2425);
DISPLAY 0.872340 (-1627 2425);
PAINT GREEN (-1627 2425);
DISPLAY INVISIBLE (-1627 2425);
FORCEADD TAP..6
(-1625 2475);
FORCEPROP 3 LASTPIN (-1575 2475) SIG_NAME M_L_ECC<6>
J 0
(-1565 2485);
DISPLAY 0.659574 (-1565 2485);
PAINT MONO (-1565 2485);
DISPLAY INVISIBLE (-1565 2485);
FORCEPROP 1 LASTPIN (-1575 2475) BN 6
J 0
(-1625 2485);
DISPLAY 0.617021 (-1625 2485);
PAINT PINK (-1625 2485);
FORCEPROP 2 LAST CDS_LIB mstr_standard
J 0
(-1625 2475);
DISPLAY 0.787234 (-1625 2475);
PAINT MONO (-1625 2475);
DISPLAY INVISIBLE (-1625 2475);
FORCEPROP 1 LAST BODY_TYPE PLUMBING
J 0
(-1625 2425);
DISPLAY 1.234043 (-1625 2425);
PAINT GREEN (-1625 2425);
DISPLAY INVISIBLE (-1625 2425);
FORCEPROP 1 LAST HDL_TAP TRUE
J 0
(-1300 2350);
DISPLAY 1.234043 (-1300 2350);
PAINT GREEN (-1300 2350);
DISPLAY INVISIBLE (-1300 2350);
FORCEPROP 1 LAST PATH I23
J 0
(-1627 2475);
DISPLAY 0.872340 (-1627 2475);
PAINT GREEN (-1627 2475);
DISPLAY INVISIBLE (-1627 2475);
FORCEADD TAP..6
(-1625 2525);
FORCEPROP 3 LASTPIN (-1575 2525) SIG_NAME M_L_ECC<7>
J 0
(-1565 2535);
DISPLAY 0.659574 (-1565 2535);
PAINT MONO (-1565 2535);
DISPLAY INVISIBLE (-1565 2535);
FORCEPROP 1 LASTPIN (-1575 2525) BN 7
J 0
(-1625 2535);
DISPLAY 0.617021 (-1625 2535);
PAINT PINK (-1625 2535);
FORCEPROP 2 LAST CDS_LIB mstr_standard
J 0
(-1625 2525);
DISPLAY 0.787234 (-1625 2525);
PAINT MONO (-1625 2525);
DISPLAY INVISIBLE (-1625 2525);
FORCEPROP 1 LAST BODY_TYPE PLUMBING
J 0
(-1625 2475);
DISPLAY 1.234043 (-1625 2475);
PAINT GREEN (-1625 2475);
DISPLAY INVISIBLE (-1625 2475);
FORCEPROP 1 LAST HDL_TAP TRUE
J 0
(-1300 2400);
DISPLAY 1.234043 (-1300 2400);
PAINT GREEN (-1300 2400);
DISPLAY INVISIBLE (-1300 2400);
FORCEPROP 1 LAST PATH I24
J 0
(-1627 2525);
DISPLAY 0.872340 (-1627 2525);
PAINT GREEN (-1627 2525);
DISPLAY INVISIBLE (-1627 2525);
FORCEADD TAP..6
(-1625 2675);
FORCEPROP 3 LASTPIN (-1575 2675) SIG_NAME M_L_ODT<3>
J 0
(-1565 2685);
DISPLAY 0.659574 (-1565 2685);
PAINT MONO (-1565 2685);
DISPLAY INVISIBLE (-1565 2685);
FORCEPROP 1 LASTPIN (-1575 2675) BN 3
J 0
(-1625 2685);
DISPLAY 0.617021 (-1625 2685);
PAINT PINK (-1625 2685);
FORCEPROP 2 LAST CDS_LIB mstr_standard
J 0
(-1625 2675);
DISPLAY 0.787234 (-1625 2675);
PAINT MONO (-1625 2675);
DISPLAY INVISIBLE (-1625 2675);
FORCEPROP 1 LAST BODY_TYPE PLUMBING
J 0
(-1625 2625);
DISPLAY 1.234043 (-1625 2625);
PAINT GREEN (-1625 2625);
DISPLAY INVISIBLE (-1625 2625);
FORCEPROP 1 LAST HDL_TAP TRUE
J 0
(-1300 2550);
DISPLAY 1.234043 (-1300 2550);
PAINT GREEN (-1300 2550);
DISPLAY INVISIBLE (-1300 2550);
FORCEPROP 1 LAST PATH I25
J 0
(-1627 2675);
DISPLAY 0.872340 (-1627 2675);
PAINT GREEN (-1627 2675);
DISPLAY INVISIBLE (-1627 2675);
FORCEADD TAP..6
(-1625 2625);
FORCEPROP 3 LASTPIN (-1575 2625) SIG_NAME M_L_ODT<2>
J 0
(-1565 2635);
DISPLAY 0.659574 (-1565 2635);
PAINT MONO (-1565 2635);
DISPLAY INVISIBLE (-1565 2635);
FORCEPROP 1 LASTPIN (-1575 2625) BN 2
J 0
(-1625 2635);
DISPLAY 0.617021 (-1625 2635);
PAINT PINK (-1625 2635);
FORCEPROP 2 LAST CDS_LIB mstr_standard
J 0
(-1625 2625);
DISPLAY 0.787234 (-1625 2625);
PAINT MONO (-1625 2625);
DISPLAY INVISIBLE (-1625 2625);
FORCEPROP 1 LAST BODY_TYPE PLUMBING
J 0
(-1625 2575);
DISPLAY 1.234043 (-1625 2575);
PAINT GREEN (-1625 2575);
DISPLAY INVISIBLE (-1625 2575);
FORCEPROP 1 LAST HDL_TAP TRUE
J 0
(-1300 2500);
DISPLAY 1.234043 (-1300 2500);
PAINT GREEN (-1300 2500);
DISPLAY INVISIBLE (-1300 2500);
FORCEPROP 1 LAST PATH I26
J 0
(-1627 2625);
DISPLAY 0.872340 (-1627 2625);
PAINT GREEN (-1627 2625);
DISPLAY INVISIBLE (-1627 2625);
FORCEADD OFFPAGE..1
(-2225 2875);
FORCEPROP 2 LAST $XR0 61 
J 0
(-2476 2875);
DISPLAY 0.638298 (-2476 2875);
PAINT MONO (-2476 2875);
FORCEPROP 2 LAST $XR1 85 
J 0
(-2566 2875);
DISPLAY 0.638298 (-2566 2875);
PAINT MONO (-2566 2875);
FORCEPROP 2 LAST CDS_LIB mstr_standard
J 0
(-2225 2875);
DISPLAY 0.787234 (-2225 2875);
PAINT MONO (-2225 2875);
DISPLAY INVISIBLE (-2225 2875);
FORCEPROP 1 LAST OFFPAGE TRUE
J 0
(-1900 2750);
DISPLAY 0.936170 (-1900 2750);
PAINT GREEN (-1900 2750);
DISPLAY INVISIBLE (-1900 2750);
FORCEPROP 1 LAST COMMENT_BODY TRUE
J 0
(-2100 2775);
DISPLAY 0.936170 (-2100 2775);
PAINT GREEN (-2100 2775);
DISPLAY INVISIBLE (-2100 2775);
FORCEPROP 2 LAST PATH I27
J 0
(-2475 2925);
DISPLAY 1.021277 (-2475 2925);
PAINT ORANGE (-2475 2925);
DISPLAY INVISIBLE (-2475 2925);
FORCEADD OFFPAGE..1
(-2225 3125);
FORCEPROP 2 LAST $XR0 61 
J 0
(-2476 3125);
DISPLAY 0.638298 (-2476 3125);
PAINT MONO (-2476 3125);
FORCEPROP 2 LAST $XR1 85 
J 0
(-2566 3125);
DISPLAY 0.638298 (-2566 3125);
PAINT MONO (-2566 3125);
FORCEPROP 2 LAST CDS_LIB mstr_standard
J 0
(-2225 3125);
DISPLAY 0.787234 (-2225 3125);
PAINT MONO (-2225 3125);
DISPLAY INVISIBLE (-2225 3125);
FORCEPROP 1 LAST OFFPAGE TRUE
J 0
(-1900 3000);
DISPLAY 0.936170 (-1900 3000);
PAINT GREEN (-1900 3000);
DISPLAY INVISIBLE (-1900 3000);
FORCEPROP 1 LAST COMMENT_BODY TRUE
J 0
(-2100 3025);
DISPLAY 0.936170 (-2100 3025);
PAINT GREEN (-2100 3025);
DISPLAY INVISIBLE (-2100 3025);
FORCEPROP 2 LAST PATH I28
J 0
(-2475 3175);
DISPLAY 1.021277 (-2475 3175);
PAINT ORANGE (-2475 3175);
DISPLAY INVISIBLE (-2475 3175);
FORCEADD OFFPAGE..1
(-2225 3175);
FORCEPROP 2 LAST $XR0 61 
J 0
(-2476 3175);
DISPLAY 0.638298 (-2476 3175);
PAINT MONO (-2476 3175);
FORCEPROP 2 LAST $XR1 85 
J 0
(-2566 3175);
DISPLAY 0.638298 (-2566 3175);
PAINT MONO (-2566 3175);
FORCEPROP 2 LAST CDS_LIB mstr_standard
J 0
(-2225 3175);
DISPLAY 0.787234 (-2225 3175);
PAINT MONO (-2225 3175);
DISPLAY INVISIBLE (-2225 3175);
FORCEPROP 1 LAST OFFPAGE TRUE
J 0
(-1900 3050);
DISPLAY 0.936170 (-1900 3050);
PAINT GREEN (-1900 3050);
DISPLAY INVISIBLE (-1900 3050);
FORCEPROP 1 LAST COMMENT_BODY TRUE
J 0
(-2100 3075);
DISPLAY 0.936170 (-2100 3075);
PAINT GREEN (-2100 3075);
DISPLAY INVISIBLE (-2100 3075);
FORCEPROP 2 LAST PATH I29
J 0
(-2475 3225);
DISPLAY 1.021277 (-2475 3225);
PAINT ORANGE (-2475 3225);
DISPLAY INVISIBLE (-2475 3225);
FORCEADD OFFPAGE..1
(-2225 3375);
FORCEPROP 2 LAST $XR0 61 
J 0
(-2476 3375);
DISPLAY 0.638298 (-2476 3375);
PAINT MONO (-2476 3375);
FORCEPROP 2 LAST $XR1 85 
J 0
(-2566 3375);
DISPLAY 0.638298 (-2566 3375);
PAINT MONO (-2566 3375);
FORCEPROP 2 LAST CDS_LIB mstr_standard
J 0
(-2225 3375);
DISPLAY 0.787234 (-2225 3375);
PAINT MONO (-2225 3375);
DISPLAY INVISIBLE (-2225 3375);
FORCEPROP 1 LAST OFFPAGE TRUE
J 0
(-1900 3250);
DISPLAY 0.936170 (-1900 3250);
PAINT GREEN (-1900 3250);
DISPLAY INVISIBLE (-1900 3250);
FORCEPROP 1 LAST COMMENT_BODY TRUE
J 0
(-2100 3275);
DISPLAY 0.936170 (-2100 3275);
PAINT GREEN (-2100 3275);
DISPLAY INVISIBLE (-2100 3275);
FORCEPROP 2 LAST PATH I30
J 0
(-2475 3425);
DISPLAY 1.021277 (-2475 3425);
PAINT ORANGE (-2475 3425);
DISPLAY INVISIBLE (-2475 3425);
FORCEADD OFFPAGE..1
(-2225 3425);
FORCEPROP 2 LAST $XR0 61 
J 0
(-2476 3425);
DISPLAY 0.638298 (-2476 3425);
PAINT MONO (-2476 3425);
FORCEPROP 2 LAST $XR1 85 
J 0
(-2566 3425);
DISPLAY 0.638298 (-2566 3425);
PAINT MONO (-2566 3425);
FORCEPROP 2 LAST CDS_LIB mstr_standard
J 0
(-2225 3425);
DISPLAY 0.787234 (-2225 3425);
PAINT MONO (-2225 3425);
DISPLAY INVISIBLE (-2225 3425);
FORCEPROP 1 LAST OFFPAGE TRUE
J 0
(-1900 3300);
DISPLAY 0.936170 (-1900 3300);
PAINT GREEN (-1900 3300);
DISPLAY INVISIBLE (-1900 3300);
FORCEPROP 1 LAST COMMENT_BODY TRUE
J 0
(-2100 3325);
DISPLAY 0.936170 (-2100 3325);
PAINT GREEN (-2100 3325);
DISPLAY INVISIBLE (-2100 3325);
FORCEPROP 2 LAST PATH I31
J 0
(-2475 3475);
DISPLAY 1.021277 (-2475 3475);
PAINT ORANGE (-2475 3475);
DISPLAY INVISIBLE (-2475 3475);
FORCEADD OFFPAGE..1
(-2225 3550);
FORCEPROP 2 LAST $XR0 61 
J 0
(-2476 3550);
DISPLAY 0.638298 (-2476 3550);
PAINT MONO (-2476 3550);
FORCEPROP 2 LAST $XR1 85 
J 0
(-2566 3550);
DISPLAY 0.638298 (-2566 3550);
PAINT MONO (-2566 3550);
FORCEPROP 2 LAST CDS_LIB mstr_standard
J 0
(-2225 3550);
DISPLAY 0.787234 (-2225 3550);
PAINT MONO (-2225 3550);
DISPLAY INVISIBLE (-2225 3550);
FORCEPROP 1 LAST OFFPAGE TRUE
J 0
(-1900 3425);
DISPLAY 0.936170 (-1900 3425);
PAINT GREEN (-1900 3425);
DISPLAY INVISIBLE (-1900 3425);
FORCEPROP 1 LAST COMMENT_BODY TRUE
J 0
(-2100 3450);
DISPLAY 0.936170 (-2100 3450);
PAINT GREEN (-2100 3450);
DISPLAY INVISIBLE (-2100 3450);
FORCEPROP 2 LAST PATH I32
J 0
(-2475 3600);
DISPLAY 1.021277 (-2475 3600);
PAINT ORANGE (-2475 3600);
DISPLAY INVISIBLE (-2475 3600);
FORCEADD OFFPAGE..1
(-2225 3675);
FORCEPROP 2 LAST $XR0 61 
J 0
(-2476 3675);
DISPLAY 0.638298 (-2476 3675);
PAINT MONO (-2476 3675);
FORCEPROP 2 LAST $XR1 85 
J 0
(-2566 3675);
DISPLAY 0.638298 (-2566 3675);
PAINT MONO (-2566 3675);
FORCEPROP 2 LAST CDS_LIB mstr_standard
J 0
(-2225 3675);
DISPLAY 0.787234 (-2225 3675);
PAINT MONO (-2225 3675);
DISPLAY INVISIBLE (-2225 3675);
FORCEPROP 1 LAST OFFPAGE TRUE
J 0
(-1900 3550);
DISPLAY 0.936170 (-1900 3550);
PAINT GREEN (-1900 3550);
DISPLAY INVISIBLE (-1900 3550);
FORCEPROP 1 LAST COMMENT_BODY TRUE
J 0
(-2100 3575);
DISPLAY 0.936170 (-2100 3575);
PAINT GREEN (-2100 3575);
DISPLAY INVISIBLE (-2100 3575);
FORCEPROP 2 LAST PATH I33
J 0
(-2475 3725);
DISPLAY 1.021277 (-2475 3725);
PAINT ORANGE (-2475 3725);
DISPLAY INVISIBLE (-2475 3725);
FORCEADD TAP..6
(-1825 3225);
FORCEPROP 3 LASTPIN (-1775 3225) SIG_NAME M_L_CLK_DN<2>
J 0
(-1765 3235);
DISPLAY 0.659574 (-1765 3235);
PAINT MONO (-1765 3235);
DISPLAY INVISIBLE (-1765 3235);
FORCEPROP 1 LASTPIN (-1775 3225) BN 2
J 0
(-1825 3235);
DISPLAY 0.617021 (-1825 3235);
PAINT PINK (-1825 3235);
FORCEPROP 2 LAST CDS_LIB mstr_standard
J 0
(-1825 3225);
DISPLAY 0.787234 (-1825 3225);
PAINT MONO (-1825 3225);
DISPLAY INVISIBLE (-1825 3225);
FORCEPROP 1 LAST BODY_TYPE PLUMBING
J 0
(-1825 3175);
DISPLAY 1.234043 (-1825 3175);
PAINT GREEN (-1825 3175);
DISPLAY INVISIBLE (-1825 3175);
FORCEPROP 1 LAST HDL_TAP TRUE
J 0
(-1500 3100);
DISPLAY 1.234043 (-1500 3100);
PAINT GREEN (-1500 3100);
DISPLAY INVISIBLE (-1500 3100);
FORCEPROP 1 LAST PATH I34
J 0
(-1827 3225);
DISPLAY 0.872340 (-1827 3225);
PAINT GREEN (-1827 3225);
DISPLAY INVISIBLE (-1827 3225);
FORCEADD TAP..6
(-1625 2825);
FORCEPROP 3 LASTPIN (-1575 2825) SIG_NAME M_L_CKE<3>
J 0
(-1565 2835);
DISPLAY 0.659574 (-1565 2835);
PAINT MONO (-1565 2835);
DISPLAY INVISIBLE (-1565 2835);
FORCEPROP 1 LASTPIN (-1575 2825) BN 3
J 0
(-1625 2835);
DISPLAY 0.617021 (-1625 2835);
PAINT PINK (-1625 2835);
FORCEPROP 2 LAST CDS_LIB mstr_standard
J 0
(-1625 2825);
DISPLAY 0.787234 (-1625 2825);
PAINT MONO (-1625 2825);
DISPLAY INVISIBLE (-1625 2825);
FORCEPROP 1 LAST BODY_TYPE PLUMBING
J 0
(-1625 2775);
DISPLAY 1.234043 (-1625 2775);
PAINT GREEN (-1625 2775);
DISPLAY INVISIBLE (-1625 2775);
FORCEPROP 1 LAST HDL_TAP TRUE
J 0
(-1300 2700);
DISPLAY 1.234043 (-1300 2700);
PAINT GREEN (-1300 2700);
DISPLAY INVISIBLE (-1300 2700);
FORCEPROP 1 LAST PATH I35
J 0
(-1627 2825);
DISPLAY 0.872340 (-1627 2825);
PAINT GREEN (-1627 2825);
DISPLAY INVISIBLE (-1627 2825);
FORCEADD TAP..6
(-1625 2775);
FORCEPROP 3 LASTPIN (-1575 2775) SIG_NAME M_L_CKE<2>
J 0
(-1565 2785);
DISPLAY 0.659574 (-1565 2785);
PAINT MONO (-1565 2785);
DISPLAY INVISIBLE (-1565 2785);
FORCEPROP 1 LASTPIN (-1575 2775) BN 2
J 0
(-1625 2785);
DISPLAY 0.617021 (-1625 2785);
PAINT PINK (-1625 2785);
FORCEPROP 2 LAST CDS_LIB mstr_standard
J 0
(-1625 2775);
DISPLAY 0.787234 (-1625 2775);
PAINT MONO (-1625 2775);
DISPLAY INVISIBLE (-1625 2775);
FORCEPROP 1 LAST BODY_TYPE PLUMBING
J 0
(-1625 2725);
DISPLAY 1.234043 (-1625 2725);
PAINT GREEN (-1625 2725);
DISPLAY INVISIBLE (-1625 2725);
FORCEPROP 1 LAST HDL_TAP TRUE
J 0
(-1300 2650);
DISPLAY 1.234043 (-1300 2650);
PAINT GREEN (-1300 2650);
DISPLAY INVISIBLE (-1300 2650);
FORCEPROP 1 LAST PATH I36
J 0
(-1627 2775);
DISPLAY 0.872340 (-1627 2775);
PAINT GREEN (-1627 2775);
DISPLAY INVISIBLE (-1627 2775);
FORCEADD TAP..6
(-1625 2975);
FORCEPROP 3 LASTPIN (-1575 2975) SIG_NAME M_L_CS_N<5>
J 0
(-1565 2985);
DISPLAY 0.659574 (-1565 2985);
PAINT MONO (-1565 2985);
DISPLAY INVISIBLE (-1565 2985);
FORCEPROP 1 LASTPIN (-1575 2975) BN 5
J 0
(-1625 2985);
DISPLAY 0.617021 (-1625 2985);
PAINT PINK (-1625 2985);
FORCEPROP 2 LAST CDS_LIB mstr_standard
J 0
(-1625 2975);
DISPLAY 0.787234 (-1625 2975);
PAINT MONO (-1625 2975);
DISPLAY INVISIBLE (-1625 2975);
FORCEPROP 1 LAST BODY_TYPE PLUMBING
J 0
(-1625 2925);
DISPLAY 1.234043 (-1625 2925);
PAINT GREEN (-1625 2925);
DISPLAY INVISIBLE (-1625 2925);
FORCEPROP 1 LAST HDL_TAP TRUE
J 0
(-1300 2850);
DISPLAY 1.234043 (-1300 2850);
PAINT GREEN (-1300 2850);
DISPLAY INVISIBLE (-1300 2850);
FORCEPROP 1 LAST PATH I37
J 0
(-1627 2975);
DISPLAY 0.872340 (-1627 2975);
PAINT GREEN (-1627 2975);
DISPLAY INVISIBLE (-1627 2975);
FORCEADD TAP..6
(-1625 2925);
FORCEPROP 3 LASTPIN (-1575 2925) SIG_NAME M_L_CS_N<4>
J 0
(-1565 2935);
DISPLAY 0.659574 (-1565 2935);
PAINT MONO (-1565 2935);
DISPLAY INVISIBLE (-1565 2935);
FORCEPROP 1 LASTPIN (-1575 2925) BN 4
J 0
(-1625 2935);
DISPLAY 0.617021 (-1625 2935);
PAINT PINK (-1625 2935);
FORCEPROP 2 LAST CDS_LIB mstr_standard
J 0
(-1625 2925);
DISPLAY 0.787234 (-1625 2925);
PAINT MONO (-1625 2925);
DISPLAY INVISIBLE (-1625 2925);
FORCEPROP 1 LAST BODY_TYPE PLUMBING
J 0
(-1625 2875);
DISPLAY 1.234043 (-1625 2875);
PAINT GREEN (-1625 2875);
DISPLAY INVISIBLE (-1625 2875);
FORCEPROP 1 LAST HDL_TAP TRUE
J 0
(-1300 2800);
DISPLAY 1.234043 (-1300 2800);
PAINT GREEN (-1300 2800);
DISPLAY INVISIBLE (-1300 2800);
FORCEPROP 1 LAST PATH I38
J 0
(-1627 2925);
DISPLAY 0.872340 (-1627 2925);
PAINT GREEN (-1627 2925);
DISPLAY INVISIBLE (-1627 2925);
FORCEADD TAP..6
(-1625 3075);
FORCEPROP 3 LASTPIN (-1575 3075) SIG_NAME M_L_CS_N<7>
J 0
(-1565 3085);
DISPLAY 0.659574 (-1565 3085);
PAINT MONO (-1565 3085);
DISPLAY INVISIBLE (-1565 3085);
FORCEPROP 1 LASTPIN (-1575 3075) BN 7
J 0
(-1625 3085);
DISPLAY 0.617021 (-1625 3085);
PAINT PINK (-1625 3085);
FORCEPROP 2 LAST CDS_LIB mstr_standard
J 0
(-1625 3075);
DISPLAY 0.787234 (-1625 3075);
PAINT MONO (-1625 3075);
DISPLAY INVISIBLE (-1625 3075);
FORCEPROP 1 LAST BODY_TYPE PLUMBING
J 0
(-1625 3025);
DISPLAY 1.234043 (-1625 3025);
PAINT GREEN (-1625 3025);
DISPLAY INVISIBLE (-1625 3025);
FORCEPROP 1 LAST HDL_TAP TRUE
J 0
(-1300 2950);
DISPLAY 1.234043 (-1300 2950);
PAINT GREEN (-1300 2950);
DISPLAY INVISIBLE (-1300 2950);
FORCEPROP 1 LAST PATH I39
J 0
(-1627 3075);
DISPLAY 0.872340 (-1627 3075);
PAINT GREEN (-1627 3075);
DISPLAY INVISIBLE (-1627 3075);
FORCEADD OFFPAGE..1
(-3175 1425);
FORCEPROP 2 LAST $XR0 100 
J 0
(-3427 1425);
DISPLAY 0.638298 (-3427 1425);
PAINT MONO (-3427 1425);
FORCEPROP 2 LAST $XR1 85 
J 0
(-3517 1425);
DISPLAY 0.638298 (-3517 1425);
PAINT MONO (-3517 1425);
FORCEPROP 2 LAST CDS_LIB mstr_standard
J 0
(-3175 1425);
DISPLAY 0.787234 (-3175 1425);
PAINT MONO (-3175 1425);
DISPLAY INVISIBLE (-3175 1425);
FORCEPROP 1 LAST OFFPAGE TRUE
J 0
(-2850 1300);
DISPLAY 0.936170 (-2850 1300);
PAINT GREEN (-2850 1300);
DISPLAY INVISIBLE (-2850 1300);
FORCEPROP 1 LAST COMMENT_BODY TRUE
J 0
(-3050 1325);
DISPLAY 0.936170 (-3050 1325);
PAINT GREEN (-3050 1325);
DISPLAY INVISIBLE (-3050 1325);
FORCEPROP 2 LAST PATH I4
J 0
(-3425 1475);
DISPLAY 1.021277 (-3425 1475);
PAINT ORANGE (-3425 1475);
DISPLAY INVISIBLE (-3425 1475);
FORCEADD TAP..6
(-1625 3025);
FORCEPROP 3 LASTPIN (-1575 3025) SIG_NAME M_L_CS_N<6>
J 0
(-1565 3035);
DISPLAY 0.659574 (-1565 3035);
PAINT MONO (-1565 3035);
DISPLAY INVISIBLE (-1565 3035);
FORCEPROP 1 LASTPIN (-1575 3025) BN 6
J 0
(-1625 3035);
DISPLAY 0.617021 (-1625 3035);
PAINT PINK (-1625 3035);
FORCEPROP 2 LAST CDS_LIB mstr_standard
J 0
(-1625 3025);
DISPLAY 0.787234 (-1625 3025);
PAINT MONO (-1625 3025);
DISPLAY INVISIBLE (-1625 3025);
FORCEPROP 1 LAST BODY_TYPE PLUMBING
J 0
(-1625 2975);
DISPLAY 1.234043 (-1625 2975);
PAINT GREEN (-1625 2975);
DISPLAY INVISIBLE (-1625 2975);
FORCEPROP 1 LAST HDL_TAP TRUE
J 0
(-1300 2900);
DISPLAY 1.234043 (-1300 2900);
PAINT GREEN (-1300 2900);
DISPLAY INVISIBLE (-1300 2900);
FORCEPROP 1 LAST PATH I40
J 0
(-1627 3025);
DISPLAY 0.872340 (-1627 3025);
PAINT GREEN (-1627 3025);
DISPLAY INVISIBLE (-1627 3025);
FORCEADD TAP..6
(-1825 3325);
FORCEPROP 3 LASTPIN (-1775 3325) SIG_NAME M_L_CLK_DN<3>
J 0
(-1765 3335);
DISPLAY 0.659574 (-1765 3335);
PAINT MONO (-1765 3335);
DISPLAY INVISIBLE (-1765 3335);
FORCEPROP 1 LASTPIN (-1775 3325) BN 3
J 0
(-1825 3335);
DISPLAY 0.617021 (-1825 3335);
PAINT PINK (-1825 3335);
FORCEPROP 2 LAST CDS_LIB mstr_standard
J 0
(-1825 3325);
DISPLAY 0.787234 (-1825 3325);
PAINT MONO (-1825 3325);
DISPLAY INVISIBLE (-1825 3325);
FORCEPROP 1 LAST BODY_TYPE PLUMBING
J 0
(-1825 3275);
DISPLAY 1.234043 (-1825 3275);
PAINT GREEN (-1825 3275);
DISPLAY INVISIBLE (-1825 3275);
FORCEPROP 1 LAST HDL_TAP TRUE
J 0
(-1500 3200);
DISPLAY 1.234043 (-1500 3200);
PAINT GREEN (-1500 3200);
DISPLAY INVISIBLE (-1500 3200);
FORCEPROP 1 LAST PATH I41
J 0
(-1827 3325);
DISPLAY 0.872340 (-1827 3325);
PAINT GREEN (-1827 3325);
DISPLAY INVISIBLE (-1827 3325);
FORCEADD TAP..6
(-1625 3275);
FORCEPROP 3 LASTPIN (-1575 3275) SIG_NAME M_L_CLK_DP<2>
J 0
(-1565 3285);
DISPLAY 0.659574 (-1565 3285);
PAINT MONO (-1565 3285);
DISPLAY INVISIBLE (-1565 3285);
FORCEPROP 1 LASTPIN (-1575 3275) BN 2
J 0
(-1625 3285);
DISPLAY 0.617021 (-1625 3285);
PAINT PINK (-1625 3285);
FORCEPROP 2 LAST CDS_LIB mstr_standard
J 0
(-1625 3275);
DISPLAY 0.787234 (-1625 3275);
PAINT MONO (-1625 3275);
DISPLAY INVISIBLE (-1625 3275);
FORCEPROP 1 LAST BODY_TYPE PLUMBING
J 0
(-1625 3225);
DISPLAY 1.234043 (-1625 3225);
PAINT GREEN (-1625 3225);
DISPLAY INVISIBLE (-1625 3225);
FORCEPROP 1 LAST HDL_TAP TRUE
J 0
(-1300 3150);
DISPLAY 1.234043 (-1300 3150);
PAINT GREEN (-1300 3150);
DISPLAY INVISIBLE (-1300 3150);
FORCEPROP 1 LAST PATH I42
J 0
(-1627 3275);
DISPLAY 0.872340 (-1627 3275);
PAINT GREEN (-1627 3275);
DISPLAY INVISIBLE (-1627 3275);
FORCEADD TAP..6
(-1625 3375);
FORCEPROP 3 LASTPIN (-1575 3375) SIG_NAME M_L_CLK_DP<3>
J 0
(-1565 3385);
DISPLAY 0.659574 (-1565 3385);
PAINT MONO (-1565 3385);
DISPLAY INVISIBLE (-1565 3385);
FORCEPROP 1 LASTPIN (-1575 3375) BN 3
J 0
(-1625 3385);
DISPLAY 0.617021 (-1625 3385);
PAINT PINK (-1625 3385);
FORCEPROP 2 LAST CDS_LIB mstr_standard
J 0
(-1625 3375);
DISPLAY 0.787234 (-1625 3375);
PAINT MONO (-1625 3375);
DISPLAY INVISIBLE (-1625 3375);
FORCEPROP 1 LAST BODY_TYPE PLUMBING
J 0
(-1625 3325);
DISPLAY 1.234043 (-1625 3325);
PAINT GREEN (-1625 3325);
DISPLAY INVISIBLE (-1625 3325);
FORCEPROP 1 LAST HDL_TAP TRUE
J 0
(-1300 3250);
DISPLAY 1.234043 (-1300 3250);
PAINT GREEN (-1300 3250);
DISPLAY INVISIBLE (-1300 3250);
FORCEPROP 1 LAST PATH I43
J 0
(-1627 3375);
DISPLAY 0.872340 (-1627 3375);
PAINT GREEN (-1627 3375);
DISPLAY INVISIBLE (-1627 3375);
FORCEADD TAP..6
(-1625 3475);
FORCEPROP 3 LASTPIN (-1575 3475) SIG_NAME M_L_BG<0>
J 0
(-1565 3485);
DISPLAY 0.659574 (-1565 3485);
PAINT MONO (-1565 3485);
DISPLAY INVISIBLE (-1565 3485);
FORCEPROP 1 LASTPIN (-1575 3475) BN 0
J 0
(-1625 3485);
DISPLAY 0.617021 (-1625 3485);
PAINT PINK (-1625 3485);
FORCEPROP 2 LAST CDS_LIB mstr_standard
J 0
(-1625 3475);
DISPLAY 0.787234 (-1625 3475);
PAINT MONO (-1625 3475);
DISPLAY INVISIBLE (-1625 3475);
FORCEPROP 1 LAST BODY_TYPE PLUMBING
J 0
(-1625 3425);
DISPLAY 1.234043 (-1625 3425);
PAINT GREEN (-1625 3425);
DISPLAY INVISIBLE (-1625 3425);
FORCEPROP 1 LAST HDL_TAP TRUE
J 0
(-1300 3350);
DISPLAY 1.234043 (-1300 3350);
PAINT GREEN (-1300 3350);
DISPLAY INVISIBLE (-1300 3350);
FORCEPROP 1 LAST PATH I44
J 0
(-1627 3475);
DISPLAY 0.872340 (-1627 3475);
PAINT GREEN (-1627 3475);
DISPLAY INVISIBLE (-1627 3475);
FORCEADD TAP..6
(-1625 3575);
FORCEPROP 3 LASTPIN (-1575 3575) SIG_NAME M_L_BA<0>
J 0
(-1565 3585);
DISPLAY 0.659574 (-1565 3585);
PAINT MONO (-1565 3585);
DISPLAY INVISIBLE (-1565 3585);
FORCEPROP 1 LASTPIN (-1575 3575) BN 0
J 0
(-1625 3585);
DISPLAY 0.617021 (-1625 3585);
PAINT PINK (-1625 3585);
FORCEPROP 2 LAST CDS_LIB mstr_standard
J 0
(-1625 3575);
DISPLAY 0.787234 (-1625 3575);
PAINT MONO (-1625 3575);
DISPLAY INVISIBLE (-1625 3575);
FORCEPROP 1 LAST BODY_TYPE PLUMBING
J 0
(-1625 3525);
DISPLAY 1.234043 (-1625 3525);
PAINT GREEN (-1625 3525);
DISPLAY INVISIBLE (-1625 3525);
FORCEPROP 1 LAST HDL_TAP TRUE
J 0
(-1300 3450);
DISPLAY 1.234043 (-1300 3450);
PAINT GREEN (-1300 3450);
DISPLAY INVISIBLE (-1300 3450);
FORCEPROP 1 LAST PATH I45
J 0
(-1627 3575);
DISPLAY 0.872340 (-1627 3575);
PAINT GREEN (-1627 3575);
DISPLAY INVISIBLE (-1627 3575);
FORCEADD TAP..6
(-1625 3525);
FORCEPROP 3 LASTPIN (-1575 3525) SIG_NAME M_L_BG<1>
J 0
(-1565 3535);
DISPLAY 0.659574 (-1565 3535);
PAINT MONO (-1565 3535);
DISPLAY INVISIBLE (-1565 3535);
FORCEPROP 1 LASTPIN (-1575 3525) BN 1
J 0
(-1625 3535);
DISPLAY 0.617021 (-1625 3535);
PAINT PINK (-1625 3535);
FORCEPROP 2 LAST CDS_LIB mstr_standard
J 0
(-1625 3525);
DISPLAY 0.787234 (-1625 3525);
PAINT MONO (-1625 3525);
DISPLAY INVISIBLE (-1625 3525);
FORCEPROP 1 LAST BODY_TYPE PLUMBING
J 0
(-1625 3475);
DISPLAY 1.234043 (-1625 3475);
PAINT GREEN (-1625 3475);
DISPLAY INVISIBLE (-1625 3475);
FORCEPROP 1 LAST HDL_TAP TRUE
J 0
(-1300 3400);
DISPLAY 1.234043 (-1300 3400);
PAINT GREEN (-1300 3400);
DISPLAY INVISIBLE (-1300 3400);
FORCEPROP 1 LAST PATH I46
J 0
(-1627 3525);
DISPLAY 0.872340 (-1627 3525);
PAINT GREEN (-1627 3525);
DISPLAY INVISIBLE (-1627 3525);
FORCEADD TAP..6
(-1625 3625);
FORCEPROP 3 LASTPIN (-1575 3625) SIG_NAME M_L_BA<1>
J 0
(-1565 3635);
DISPLAY 0.659574 (-1565 3635);
PAINT MONO (-1565 3635);
DISPLAY INVISIBLE (-1565 3635);
FORCEPROP 1 LASTPIN (-1575 3625) BN 1
J 0
(-1625 3635);
DISPLAY 0.617021 (-1625 3635);
PAINT PINK (-1625 3635);
FORCEPROP 2 LAST CDS_LIB mstr_standard
J 0
(-1625 3625);
DISPLAY 0.787234 (-1625 3625);
PAINT MONO (-1625 3625);
DISPLAY INVISIBLE (-1625 3625);
FORCEPROP 1 LAST BODY_TYPE PLUMBING
J 0
(-1625 3575);
DISPLAY 1.234043 (-1625 3575);
PAINT GREEN (-1625 3575);
DISPLAY INVISIBLE (-1625 3575);
FORCEPROP 1 LAST HDL_TAP TRUE
J 0
(-1300 3500);
DISPLAY 1.234043 (-1300 3500);
PAINT GREEN (-1300 3500);
DISPLAY INVISIBLE (-1300 3500);
FORCEPROP 1 LAST PATH I47
J 0
(-1627 3625);
DISPLAY 0.872340 (-1627 3625);
PAINT GREEN (-1627 3625);
DISPLAY INVISIBLE (-1627 3625);
FORCEADD TAP..6
(-1625 3725);
FORCEPROP 3 LASTPIN (-1575 3725) SIG_NAME M_L_MA<0>
J 0
(-1565 3735);
DISPLAY 0.659574 (-1565 3735);
PAINT MONO (-1565 3735);
DISPLAY INVISIBLE (-1565 3735);
FORCEPROP 1 LASTPIN (-1575 3725) BN 0
J 0
(-1625 3735);
DISPLAY 0.617021 (-1625 3735);
PAINT PINK (-1625 3735);
FORCEPROP 2 LAST CDS_LIB mstr_standard
J 2
(-1625 3725);
DISPLAY 0.787234 (-1625 3725);
PAINT MONO (-1625 3725);
DISPLAY INVISIBLE (-1625 3725);
FORCEPROP 1 LAST BODY_TYPE PLUMBING
J 0
(-1625 3675);
DISPLAY 1.234043 (-1625 3675);
PAINT GREEN (-1625 3675);
DISPLAY INVISIBLE (-1625 3675);
FORCEPROP 1 LAST HDL_TAP TRUE
J 0
(-1300 3600);
DISPLAY 1.234043 (-1300 3600);
PAINT GREEN (-1300 3600);
DISPLAY INVISIBLE (-1300 3600);
FORCEPROP 1 LAST PATH I48
J 0
(-1627 3725);
DISPLAY 0.872340 (-1627 3725);
PAINT GREEN (-1627 3725);
DISPLAY INVISIBLE (-1627 3725);
FORCEADD TAP..6
R 2
(-125 1425);
FORCEPROP 3 LASTPIN (-175 1425) SIG_NAME M_L_DQ<0>
J 0
(-165 1435);
DISPLAY 0.659574 (-165 1435);
PAINT MONO (-165 1435);
DISPLAY INVISIBLE (-165 1435);
FORCEPROP 1 LASTPIN (-175 1425) BN 0
J 2
(-125 1435);
DISPLAY 0.617021 (-125 1435);
PAINT PINK (-125 1435);
FORCEPROP 2 LAST CDS_LIB mstr_standard
J 2
(-125 1425);
DISPLAY 0.787234 (-125 1425);
PAINT MONO (-125 1425);
DISPLAY INVISIBLE (-125 1425);
FORCEPROP 1 LAST BODY_TYPE PLUMBING
J 2
(-125 1375);
DISPLAY 1.234043 (-125 1375);
PAINT GREEN (-125 1375);
DISPLAY INVISIBLE (-125 1375);
FORCEPROP 1 LAST HDL_TAP TRUE
J 2
(-450 1300);
DISPLAY 1.234043 (-450 1300);
PAINT GREEN (-450 1300);
DISPLAY INVISIBLE (-450 1300);
FORCEPROP 1 LAST PATH I49
J 2
(-123 1425);
DISPLAY 0.872340 (-123 1425);
PAINT GREEN (-123 1425);
DISPLAY INVISIBLE (-123 1425);
FORCEADD PVPP_KLM..1
(-3525 1925);
FORCEPROP 3 LASTPIN (-3525 1875) SIG_NAME PVPP_KLM\g
J 0
(-3515 1885);
DISPLAY 0.659574 (-3515 1885);
PAINT MONO (-3515 1885);
DISPLAY INVISIBLE (-3515 1885);
FORCEPROP 1 LAST VOLTAGE 2.5V
J 0
(-3570 1882);
DISPLAY 0.340426 (-3570 1882);
PAINT SKYBLUE (-3570 1882);
DISPLAY INVISIBLE (-3570 1882);
FORCEPROP 0 LAST BOM_COST MEM
J 0
(-3525 2025);
PAINT ORANGE (-3525 2025);
DISPLAY INVISIBLE (-3525 2025);
FORCEPROP 2 LAST CDS_LIB mstr_symbols
J 0
(-3525 1925);
PAINT ORANGE (-3525 1925);
DISPLAY INVISIBLE (-3525 1925);
FORCEPROP 1 LAST BODY_TYPE PLUMBING
J 0
(-3570 1882);
DISPLAY 0.340426 (-3570 1882);
PAINT GREEN (-3570 1882);
DISPLAY INVISIBLE (-3570 1882);
FORCEPROP 1 LAST PATH I5
J 0
(-3475 1950);
DISPLAY 0.872340 (-3475 1950);
PAINT AQUA (-3475 1950);
DISPLAY INVISIBLE (-3475 1950);
FORCEPROP 2 LAST ROOM DDR4_CH_D
J 0
(-3525 2025);
PAINT ORANGE (-3525 2025);
DISPLAY INVISIBLE (-3525 2025);
FORCEPROP 1 LAST HDL_POWER PVPP_KLM
J 1
(-3525 1975);
DISPLAY 0.872340 (-3525 1975);
PAINT GREEN (-3525 1975);
DISPLAY INVISIBLE (-3525 1975);
FORCEADD TAP..6
R 2
(-125 1625);
FORCEPROP 3 LASTPIN (-175 1625) SIG_NAME M_L_DQ<4>
J 0
(-165 1635);
DISPLAY 0.659574 (-165 1635);
PAINT MONO (-165 1635);
DISPLAY INVISIBLE (-165 1635);
FORCEPROP 1 LASTPIN (-175 1625) BN 4
J 2
(-125 1635);
DISPLAY 0.617021 (-125 1635);
PAINT PINK (-125 1635);
FORCEPROP 2 LAST CDS_LIB mstr_standard
J 2
(-125 1625);
DISPLAY 0.787234 (-125 1625);
PAINT MONO (-125 1625);
DISPLAY INVISIBLE (-125 1625);
FORCEPROP 1 LAST BODY_TYPE PLUMBING
J 2
(-125 1575);
DISPLAY 1.234043 (-125 1575);
PAINT GREEN (-125 1575);
DISPLAY INVISIBLE (-125 1575);
FORCEPROP 1 LAST HDL_TAP TRUE
J 2
(-450 1500);
DISPLAY 1.234043 (-450 1500);
PAINT GREEN (-450 1500);
DISPLAY INVISIBLE (-450 1500);
FORCEPROP 1 LAST PATH I50
J 2
(-123 1625);
DISPLAY 0.872340 (-123 1625);
PAINT GREEN (-123 1625);
DISPLAY INVISIBLE (-123 1625);
FORCEADD TAP..6
R 2
(-125 1475);
FORCEPROP 3 LASTPIN (-175 1475) SIG_NAME M_L_DQ<1>
J 0
(-165 1485);
DISPLAY 0.659574 (-165 1485);
PAINT MONO (-165 1485);
DISPLAY INVISIBLE (-165 1485);
FORCEPROP 1 LASTPIN (-175 1475) BN 1
J 2
(-125 1485);
DISPLAY 0.617021 (-125 1485);
PAINT PINK (-125 1485);
FORCEPROP 2 LAST CDS_LIB mstr_standard
J 2
(-125 1475);
DISPLAY 0.787234 (-125 1475);
PAINT MONO (-125 1475);
DISPLAY INVISIBLE (-125 1475);
FORCEPROP 1 LAST BODY_TYPE PLUMBING
J 2
(-125 1425);
DISPLAY 1.234043 (-125 1425);
PAINT GREEN (-125 1425);
DISPLAY INVISIBLE (-125 1425);
FORCEPROP 1 LAST HDL_TAP TRUE
J 2
(-450 1350);
DISPLAY 1.234043 (-450 1350);
PAINT GREEN (-450 1350);
DISPLAY INVISIBLE (-450 1350);
FORCEPROP 1 LAST PATH I51
J 2
(-123 1475);
DISPLAY 0.872340 (-123 1475);
PAINT GREEN (-123 1475);
DISPLAY INVISIBLE (-123 1475);
FORCEADD TAP..6
R 2
(-125 1525);
FORCEPROP 3 LASTPIN (-175 1525) SIG_NAME M_L_DQ<2>
J 0
(-165 1535);
DISPLAY 0.659574 (-165 1535);
PAINT MONO (-165 1535);
DISPLAY INVISIBLE (-165 1535);
FORCEPROP 1 LASTPIN (-175 1525) BN 2
J 2
(-125 1535);
DISPLAY 0.617021 (-125 1535);
PAINT PINK (-125 1535);
FORCEPROP 2 LAST CDS_LIB mstr_standard
J 2
(-125 1525);
DISPLAY 0.787234 (-125 1525);
PAINT MONO (-125 1525);
DISPLAY INVISIBLE (-125 1525);
FORCEPROP 1 LAST BODY_TYPE PLUMBING
J 2
(-125 1475);
DISPLAY 1.234043 (-125 1475);
PAINT GREEN (-125 1475);
DISPLAY INVISIBLE (-125 1475);
FORCEPROP 1 LAST HDL_TAP TRUE
J 2
(-450 1400);
DISPLAY 1.234043 (-450 1400);
PAINT GREEN (-450 1400);
DISPLAY INVISIBLE (-450 1400);
FORCEPROP 1 LAST PATH I52
J 2
(-123 1525);
DISPLAY 0.872340 (-123 1525);
PAINT GREEN (-123 1525);
DISPLAY INVISIBLE (-123 1525);
FORCEADD TAP..6
R 2
(-125 1675);
FORCEPROP 3 LASTPIN (-175 1675) SIG_NAME M_L_DQ<5>
J 0
(-165 1685);
DISPLAY 0.659574 (-165 1685);
PAINT MONO (-165 1685);
DISPLAY INVISIBLE (-165 1685);
FORCEPROP 1 LASTPIN (-175 1675) BN 5
J 2
(-125 1685);
DISPLAY 0.617021 (-125 1685);
PAINT PINK (-125 1685);
FORCEPROP 2 LAST CDS_LIB mstr_standard
J 2
(-125 1675);
DISPLAY 0.787234 (-125 1675);
PAINT MONO (-125 1675);
DISPLAY INVISIBLE (-125 1675);
FORCEPROP 1 LAST BODY_TYPE PLUMBING
J 2
(-125 1625);
DISPLAY 1.234043 (-125 1625);
PAINT GREEN (-125 1625);
DISPLAY INVISIBLE (-125 1625);
FORCEPROP 1 LAST HDL_TAP TRUE
J 2
(-450 1550);
DISPLAY 1.234043 (-450 1550);
PAINT GREEN (-450 1550);
DISPLAY INVISIBLE (-450 1550);
FORCEPROP 1 LAST PATH I53
J 2
(-123 1675);
DISPLAY 0.872340 (-123 1675);
PAINT GREEN (-123 1675);
DISPLAY INVISIBLE (-123 1675);
FORCEADD TAP..6
R 2
(-125 1575);
FORCEPROP 3 LASTPIN (-175 1575) SIG_NAME M_L_DQ<3>
J 0
(-165 1585);
DISPLAY 0.659574 (-165 1585);
PAINT MONO (-165 1585);
DISPLAY INVISIBLE (-165 1585);
FORCEPROP 1 LASTPIN (-175 1575) BN 3
J 2
(-125 1585);
DISPLAY 0.617021 (-125 1585);
PAINT PINK (-125 1585);
FORCEPROP 2 LAST CDS_LIB mstr_standard
J 2
(-125 1575);
DISPLAY 0.787234 (-125 1575);
PAINT MONO (-125 1575);
DISPLAY INVISIBLE (-125 1575);
FORCEPROP 1 LAST BODY_TYPE PLUMBING
J 2
(-125 1525);
DISPLAY 1.234043 (-125 1525);
PAINT GREEN (-125 1525);
DISPLAY INVISIBLE (-125 1525);
FORCEPROP 1 LAST HDL_TAP TRUE
J 2
(-450 1450);
DISPLAY 1.234043 (-450 1450);
PAINT GREEN (-450 1450);
DISPLAY INVISIBLE (-450 1450);
FORCEPROP 1 LAST PATH I54
J 2
(-123 1575);
DISPLAY 0.872340 (-123 1575);
PAINT GREEN (-123 1575);
DISPLAY INVISIBLE (-123 1575);
FORCEADD SCONN288_H44441003..4
(1375 1725);
FORCEPROP 1 LAST LOCATION J9L2
J 0
(925 2825);
DISPLAY 0.617021 (925 2825);
PAINT AQUA (925 2825);
FORCEPROP 1 LAST PART_NUMBER H44441-003
J 0
(925 675);
DISPLAY 0.617021 (925 675);
PAINT BLUE (925 675);
FORCEPROP 1 LAST MATERIAL SCONN
J 0
(925 2775);
DISPLAY 0.617021 (925 2775);
PAINT SKYBLUE (925 2775);
FORCEPROP 2 LASTPIN (875 2275) $PN 77
J 2
(865 2285);
DISPLAY 0.617021 (865 2285);
PAINT ORANGE (865 2285);
FORCEPROP 2 LASTPIN (875 2225) $PN 221
J 2
(865 2235);
DISPLAY 0.617021 (865 2235);
PAINT ORANGE (865 2235);
FORCEPROP 2 LASTPIN (875 2575) $PN 142
J 2
(865 2585);
DISPLAY 0.617021 (865 2585);
PAINT ORANGE (865 2585);
FORCEPROP 2 LASTPIN (875 2525) $PN 143
J 2
(865 2535);
DISPLAY 0.617021 (865 2535);
PAINT ORANGE (865 2535);
FORCEPROP 2 LASTPIN (875 2475) $PN 288
J 2
(865 2485);
DISPLAY 0.617021 (865 2485);
PAINT ORANGE (865 2485);
FORCEPROP 2 LASTPIN (875 2425) $PN 286
J 2
(865 2435);
DISPLAY 0.617021 (865 2435);
PAINT ORANGE (865 2435);
FORCEPROP 2 LASTPIN (875 2375) $PN 287
J 2
(865 2385);
DISPLAY 0.617021 (865 2385);
PAINT ORANGE (865 2385);
FORCEPROP 2 LASTPIN (875 2125) $PN 59
J 2
(865 2135);
DISPLAY 0.617021 (865 2135);
PAINT ORANGE (865 2135);
FORCEPROP 2 LASTPIN (875 2075) $PN 61
J 2
(865 2085);
DISPLAY 0.617021 (865 2085);
PAINT ORANGE (865 2085);
FORCEPROP 2 LASTPIN (875 2025) $PN 64
J 2
(865 2035);
DISPLAY 0.617021 (865 2035);
PAINT ORANGE (865 2035);
FORCEPROP 2 LASTPIN (875 1975) $PN 67
J 2
(865 1985);
DISPLAY 0.617021 (865 1985);
PAINT ORANGE (865 1985);
FORCEPROP 2 LASTPIN (875 1925) $PN 70
J 2
(865 1935);
DISPLAY 0.617021 (865 1935);
PAINT ORANGE (865 1935);
FORCEPROP 2 LASTPIN (875 1875) $PN 73
J 2
(865 1885);
DISPLAY 0.617021 (865 1885);
PAINT ORANGE (865 1885);
FORCEPROP 2 LASTPIN (875 1825) $PN 76
J 2
(865 1835);
DISPLAY 0.617021 (865 1835);
PAINT ORANGE (865 1835);
FORCEPROP 2 LASTPIN (875 1775) $PN 80
J 2
(865 1785);
DISPLAY 0.617021 (865 1785);
PAINT ORANGE (865 1785);
FORCEPROP 2 LASTPIN (875 1725) $PN 83
J 2
(865 1735);
DISPLAY 0.617021 (865 1735);
PAINT ORANGE (865 1735);
FORCEPROP 2 LASTPIN (875 1675) $PN 85
J 2
(865 1685);
DISPLAY 0.617021 (865 1685);
PAINT ORANGE (865 1685);
FORCEPROP 2 LASTPIN (875 1625) $PN 88
J 2
(865 1635);
DISPLAY 0.617021 (865 1635);
PAINT ORANGE (865 1635);
FORCEPROP 2 LASTPIN (875 1575) $PN 90
J 2
(865 1585);
DISPLAY 0.617021 (865 1585);
PAINT ORANGE (865 1585);
FORCEPROP 2 LASTPIN (875 1525) $PN 92
J 2
(865 1535);
DISPLAY 0.617021 (865 1535);
PAINT ORANGE (865 1535);
FORCEPROP 2 LASTPIN (875 1475) $PN 204
J 2
(865 1485);
DISPLAY 0.617021 (865 1485);
PAINT ORANGE (865 1485);
FORCEPROP 2 LASTPIN (875 1425) $PN 206
J 2
(865 1435);
DISPLAY 0.617021 (865 1435);
PAINT ORANGE (865 1435);
FORCEPROP 2 LASTPIN (875 1375) $PN 209
J 2
(865 1385);
DISPLAY 0.617021 (865 1385);
PAINT ORANGE (865 1385);
FORCEPROP 2 LASTPIN (875 1325) $PN 212
J 2
(865 1335);
DISPLAY 0.617021 (865 1335);
PAINT ORANGE (865 1335);
FORCEPROP 2 LASTPIN (875 1275) $PN 215
J 2
(865 1285);
DISPLAY 0.617021 (865 1285);
PAINT ORANGE (865 1285);
FORCEPROP 2 LASTPIN (875 1225) $PN 217
J 2
(865 1235);
DISPLAY 0.617021 (865 1235);
PAINT ORANGE (865 1235);
FORCEPROP 2 LASTPIN (875 1175) $PN 220
J 2
(865 1185);
DISPLAY 0.617021 (865 1185);
PAINT ORANGE (865 1185);
FORCEPROP 2 LASTPIN (875 1125) $PN 223
J 2
(865 1135);
DISPLAY 0.617021 (865 1135);
PAINT ORANGE (865 1135);
FORCEPROP 2 LASTPIN (875 1075) $PN 226
J 2
(865 1085);
DISPLAY 0.617021 (865 1085);
PAINT ORANGE (865 1085);
FORCEPROP 2 LASTPIN (875 1025) $PN 229
J 2
(865 1035);
DISPLAY 0.617021 (865 1035);
PAINT ORANGE (865 1035);
FORCEPROP 2 LASTPIN (875 975) $PN 231
J 2
(865 985);
DISPLAY 0.617021 (865 985);
PAINT ORANGE (865 985);
FORCEPROP 2 LASTPIN (875 925) $PN 233
J 2
(865 935);
DISPLAY 0.617021 (865 935);
PAINT ORANGE (865 935);
FORCEPROP 2 LASTPIN (875 875) $PN 236
J 2
(865 885);
DISPLAY 0.617021 (865 885);
PAINT ORANGE (865 885);
FORCEPROP 2 LASTPIN (1875 2575) $PN 1
J 0
(1885 2585);
DISPLAY 0.617021 (1885 2585);
PAINT ORANGE (1885 2585);
FORCEPROP 2 LASTPIN (1875 2525) $PN 145
J 0
(1885 2535);
DISPLAY 0.617021 (1885 2535);
PAINT ORANGE (1885 2535);
FORCEPROP 1 LAST PACK_TYPE PIP
J 0
(925 2875);
PAINT SKYBLUE (925 2875);
DISPLAY INVISIBLE (925 2875);
FORCEPROP 2 LAST BOM_COST MEM
J 0
(1375 1725);
PAINT ORANGE (1375 1725);
DISPLAY INVISIBLE (1375 1725);
FORCEPROP 2 LAST CDS_LIB mstr_sconn
J 0
(1375 1725);
PAINT ORANGE (1375 1725);
DISPLAY INVISIBLE (1375 1725);
FORCEPROP 2 LAST SEC_TYPE PIP
J 0
(925 2875);
DISPLAY 1.021277 (925 2875);
PAINT ORANGE (925 2875);
DISPLAY INVISIBLE (925 2875);
FORCEPROP 2 LAST SEC 4
J 0
(925 2875);
DISPLAY 0.680851 (925 2875);
PAINT MONO (925 2875);
DISPLAY INVISIBLE (925 2875);
FORCEPROP 2 LAST CDS_LOCATION J9L2
J 0
(925 2825);
DISPLAY 0.617021 (925 2825);
PAINT AQUA (925 2825);
DISPLAY INVISIBLE (925 2825);
FORCEPROP 1 LAST PATH I55
J 0
(1375 2775);
PAINT GREEN (1375 2775);
DISPLAY INVISIBLE (1375 2775);
FORCEPROP 2 LAST ROOM DDR4_CH_L
J 0
(1375 1725);
PAINT ORANGE (1375 1725);
DISPLAY INVISIBLE (1375 1725);
FORCEADD TAP..6
R 2
(-125 1925);
FORCEPROP 3 LASTPIN (-175 1925) SIG_NAME M_L_DQ<10>
J 0
(-165 1935);
DISPLAY 0.659574 (-165 1935);
PAINT MONO (-165 1935);
DISPLAY INVISIBLE (-165 1935);
FORCEPROP 1 LASTPIN (-175 1925) BN 10
J 2
(-125 1935);
DISPLAY 0.617021 (-125 1935);
PAINT PINK (-125 1935);
FORCEPROP 2 LAST CDS_LIB mstr_standard
J 2
(-125 1925);
DISPLAY 0.787234 (-125 1925);
PAINT MONO (-125 1925);
DISPLAY INVISIBLE (-125 1925);
FORCEPROP 1 LAST BODY_TYPE PLUMBING
J 2
(-125 1875);
DISPLAY 1.234043 (-125 1875);
PAINT GREEN (-125 1875);
DISPLAY INVISIBLE (-125 1875);
FORCEPROP 1 LAST HDL_TAP TRUE
J 2
(-450 1800);
DISPLAY 1.234043 (-450 1800);
PAINT GREEN (-450 1800);
DISPLAY INVISIBLE (-450 1800);
FORCEPROP 1 LAST PATH I56
J 2
(-123 1925);
DISPLAY 0.872340 (-123 1925);
PAINT GREEN (-123 1925);
DISPLAY INVISIBLE (-123 1925);
FORCEADD TAP..6
R 2
(-125 1725);
FORCEPROP 3 LASTPIN (-175 1725) SIG_NAME M_L_DQ<6>
J 0
(-165 1735);
DISPLAY 0.659574 (-165 1735);
PAINT MONO (-165 1735);
DISPLAY INVISIBLE (-165 1735);
FORCEPROP 1 LASTPIN (-175 1725) BN 6
J 2
(-125 1735);
DISPLAY 0.617021 (-125 1735);
PAINT PINK (-125 1735);
FORCEPROP 2 LAST CDS_LIB mstr_standard
J 2
(-125 1725);
DISPLAY 0.787234 (-125 1725);
PAINT MONO (-125 1725);
DISPLAY INVISIBLE (-125 1725);
FORCEPROP 1 LAST BODY_TYPE PLUMBING
J 2
(-125 1675);
DISPLAY 1.234043 (-125 1675);
PAINT GREEN (-125 1675);
DISPLAY INVISIBLE (-125 1675);
FORCEPROP 1 LAST HDL_TAP TRUE
J 2
(-450 1600);
DISPLAY 1.234043 (-450 1600);
PAINT GREEN (-450 1600);
DISPLAY INVISIBLE (-450 1600);
FORCEPROP 1 LAST PATH I57
J 2
(-123 1725);
DISPLAY 0.872340 (-123 1725);
PAINT GREEN (-123 1725);
DISPLAY INVISIBLE (-123 1725);
FORCEADD TAP..6
R 2
(-125 1825);
FORCEPROP 3 LASTPIN (-175 1825) SIG_NAME M_L_DQ<8>
J 0
(-165 1835);
DISPLAY 0.659574 (-165 1835);
PAINT MONO (-165 1835);
DISPLAY INVISIBLE (-165 1835);
FORCEPROP 1 LASTPIN (-175 1825) BN 8
J 2
(-125 1835);
DISPLAY 0.617021 (-125 1835);
PAINT PINK (-125 1835);
FORCEPROP 2 LAST CDS_LIB mstr_standard
J 2
(-125 1825);
DISPLAY 0.787234 (-125 1825);
PAINT MONO (-125 1825);
DISPLAY INVISIBLE (-125 1825);
FORCEPROP 1 LAST BODY_TYPE PLUMBING
J 2
(-125 1775);
DISPLAY 1.234043 (-125 1775);
PAINT GREEN (-125 1775);
DISPLAY INVISIBLE (-125 1775);
FORCEPROP 1 LAST HDL_TAP TRUE
J 2
(-450 1700);
DISPLAY 1.234043 (-450 1700);
PAINT GREEN (-450 1700);
DISPLAY INVISIBLE (-450 1700);
FORCEPROP 1 LAST PATH I58
J 2
(-123 1825);
DISPLAY 0.872340 (-123 1825);
PAINT GREEN (-123 1825);
DISPLAY INVISIBLE (-123 1825);
FORCEADD TAP..6
R 2
(-125 1775);
FORCEPROP 3 LASTPIN (-175 1775) SIG_NAME M_L_DQ<7>
J 0
(-165 1785);
DISPLAY 0.659574 (-165 1785);
PAINT MONO (-165 1785);
DISPLAY INVISIBLE (-165 1785);
FORCEPROP 1 LASTPIN (-175 1775) BN 7
J 2
(-125 1785);
DISPLAY 0.617021 (-125 1785);
PAINT PINK (-125 1785);
FORCEPROP 2 LAST CDS_LIB mstr_standard
J 2
(-125 1775);
DISPLAY 0.787234 (-125 1775);
PAINT MONO (-125 1775);
DISPLAY INVISIBLE (-125 1775);
FORCEPROP 1 LAST BODY_TYPE PLUMBING
J 2
(-125 1725);
DISPLAY 1.234043 (-125 1725);
PAINT GREEN (-125 1725);
DISPLAY INVISIBLE (-125 1725);
FORCEPROP 1 LAST HDL_TAP TRUE
J 2
(-450 1650);
DISPLAY 1.234043 (-450 1650);
PAINT GREEN (-450 1650);
DISPLAY INVISIBLE (-450 1650);
FORCEPROP 1 LAST PATH I59
J 2
(-123 1775);
DISPLAY 0.872340 (-123 1775);
PAINT GREEN (-123 1775);
DISPLAY INVISIBLE (-123 1775);
FORCEADD OFFPAGE..5
(-2600 2225);
FORCEPROP 2 LAST $XR0 43 
J 0
(-2824 2225);
DISPLAY 0.638298 (-2824 2225);
PAINT MONO (-2824 2225);
FORCEPROP 2 LAST $XR1 44 
J 0
(-2914 2225);
DISPLAY 0.638298 (-2914 2225);
PAINT MONO (-2914 2225);
FORCEPROP 2 LAST $XR2 45 
J 0
(-3004 2225);
DISPLAY 0.638298 (-3004 2225);
PAINT MONO (-3004 2225);
FORCEPROP 2 LAST $XR3 46 
J 0
(-3094 2225);
DISPLAY 0.638298 (-3094 2225);
PAINT MONO (-3094 2225);
FORCEPROP 2 LAST $XR4 47 
J 0
(-3184 2225);
DISPLAY 0.638298 (-3184 2225);
PAINT MONO (-3184 2225);
FORCEPROP 2 LAST $XR5 48 
J 0
(-3274 2225);
DISPLAY 0.638298 (-3274 2225);
PAINT MONO (-3274 2225);
FORCEPROP 2 LAST $XR6 49 
J 0
(-3364 2225);
DISPLAY 0.638298 (-3364 2225);
PAINT MONO (-3364 2225);
FORCEPROP 2 LAST $XR7 50 
J 0
(-3454 2225);
DISPLAY 0.638298 (-3454 2225);
PAINT MONO (-3454 2225);
FORCEPROP 2 LAST $XR8 51 
J 0
(-3544 2225);
DISPLAY 0.638298 (-3544 2225);
PAINT MONO (-3544 2225);
FORCEPROP 2 LAST $XR9 52 
J 0
(-3634 2225);
DISPLAY 0.638298 (-3634 2225);
PAINT MONO (-3634 2225);
FORCEPROP 2 LAST $XR10 53 
J 0
(-2824 2189);
DISPLAY 0.638298 (-2824 2189);
PAINT MONO (-2824 2189);
FORCEPROP 2 LAST $XR11 54 
J 0
(-2914 2189);
DISPLAY 0.638298 (-2914 2189);
PAINT MONO (-2914 2189);
FORCEPROP 2 LAST $XR12 77 
J 0
(-3004 2189);
DISPLAY 0.638298 (-3004 2189);
PAINT MONO (-3004 2189);
FORCEPROP 2 LAST $XR13 78 
J 0
(-3094 2189);
DISPLAY 0.638298 (-3094 2189);
PAINT MONO (-3094 2189);
FORCEPROP 2 LAST $XR14 79 
J 0
(-3184 2189);
DISPLAY 0.638298 (-3184 2189);
PAINT MONO (-3184 2189);
FORCEPROP 2 LAST $XR15 80 
J 0
(-3274 2189);
DISPLAY 0.638298 (-3274 2189);
PAINT MONO (-3274 2189);
FORCEPROP 2 LAST $XR16 81 
J 0
(-3364 2189);
DISPLAY 0.638298 (-3364 2189);
PAINT MONO (-3364 2189);
FORCEPROP 2 LAST $XR17 82 
J 0
(-3454 2189);
DISPLAY 0.638298 (-3454 2189);
PAINT MONO (-3454 2189);
FORCEPROP 2 LAST $XR18 83 
J 0
(-3544 2189);
DISPLAY 0.638298 (-3544 2189);
PAINT MONO (-3544 2189);
FORCEPROP 2 LAST $XR19 84 
J 0
(-3634 2189);
DISPLAY 0.638298 (-3634 2189);
PAINT MONO (-3634 2189);
FORCEPROP 2 LAST $XR20 85 
J 0
(-2824 2261);
DISPLAY 0.638298 (-2824 2261);
PAINT MONO (-2824 2261);
FORCEPROP 2 LAST $XR21 87 
J 0
(-2914 2261);
DISPLAY 0.638298 (-2914 2261);
PAINT MONO (-2914 2261);
FORCEPROP 2 LAST $XR22 88 
J 0
(-3004 2261);
DISPLAY 0.638298 (-3004 2261);
PAINT MONO (-3004 2261);
FORCEPROP 2 LAST $XR23 94 
J 0
(-3094 2261);
DISPLAY 0.638298 (-3094 2261);
PAINT MONO (-3094 2261);
FORCEPROP 2 LAST CDS_LIB mstr_standard
J 0
(-2600 2225);
DISPLAY 0.787234 (-2600 2225);
PAINT MONO (-2600 2225);
DISPLAY INVISIBLE (-2600 2225);
FORCEPROP 1 LAST OFFPAGE TRUE
J 0
(-2275 2100);
DISPLAY 1.404255 (-2275 2100);
PAINT GREEN (-2275 2100);
DISPLAY INVISIBLE (-2275 2100);
FORCEPROP 1 LAST COMMENT_BODY TRUE
J 0
(-2500 2150);
DISPLAY 1.404255 (-2500 2150);
PAINT GREEN (-2500 2150);
DISPLAY INVISIBLE (-2500 2150);
FORCEPROP 2 LAST PATH I6
J 0
(-2800 2275);
DISPLAY 1.021277 (-2800 2275);
PAINT ORANGE (-2800 2275);
DISPLAY INVISIBLE (-2800 2275);
FORCEADD TAP..6
R 2
(-125 1975);
FORCEPROP 3 LASTPIN (-175 1975) SIG_NAME M_L_DQ<11>
J 0
(-165 1985);
DISPLAY 0.659574 (-165 1985);
PAINT MONO (-165 1985);
DISPLAY INVISIBLE (-165 1985);
FORCEPROP 1 LASTPIN (-175 1975) BN 11
J 2
(-125 1985);
DISPLAY 0.617021 (-125 1985);
PAINT PINK (-125 1985);
FORCEPROP 2 LAST CDS_LIB mstr_standard
J 2
(-125 1975);
DISPLAY 0.787234 (-125 1975);
PAINT MONO (-125 1975);
DISPLAY INVISIBLE (-125 1975);
FORCEPROP 1 LAST BODY_TYPE PLUMBING
J 2
(-125 1925);
DISPLAY 1.234043 (-125 1925);
PAINT GREEN (-125 1925);
DISPLAY INVISIBLE (-125 1925);
FORCEPROP 1 LAST HDL_TAP TRUE
J 2
(-450 1850);
DISPLAY 1.234043 (-450 1850);
PAINT GREEN (-450 1850);
DISPLAY INVISIBLE (-450 1850);
FORCEPROP 1 LAST PATH I60
J 2
(-123 1975);
DISPLAY 0.872340 (-123 1975);
PAINT GREEN (-123 1975);
DISPLAY INVISIBLE (-123 1975);
FORCEADD TAP..6
R 2
(-125 1875);
FORCEPROP 3 LASTPIN (-175 1875) SIG_NAME M_L_DQ<9>
J 0
(-165 1885);
DISPLAY 0.659574 (-165 1885);
PAINT MONO (-165 1885);
DISPLAY INVISIBLE (-165 1885);
FORCEPROP 1 LASTPIN (-175 1875) BN 9
J 2
(-125 1885);
DISPLAY 0.617021 (-125 1885);
PAINT PINK (-125 1885);
FORCEPROP 2 LAST CDS_LIB mstr_standard
J 2
(-125 1875);
DISPLAY 0.787234 (-125 1875);
PAINT MONO (-125 1875);
DISPLAY INVISIBLE (-125 1875);
FORCEPROP 1 LAST BODY_TYPE PLUMBING
J 2
(-125 1825);
DISPLAY 1.234043 (-125 1825);
PAINT GREEN (-125 1825);
DISPLAY INVISIBLE (-125 1825);
FORCEPROP 1 LAST HDL_TAP TRUE
J 2
(-450 1750);
DISPLAY 1.234043 (-450 1750);
PAINT GREEN (-450 1750);
DISPLAY INVISIBLE (-450 1750);
FORCEPROP 1 LAST PATH I61
J 2
(-123 1875);
DISPLAY 0.872340 (-123 1875);
PAINT GREEN (-123 1875);
DISPLAY INVISIBLE (-123 1875);
FORCEADD TAP..6
R 2
(-125 2025);
FORCEPROP 3 LASTPIN (-175 2025) SIG_NAME M_L_DQ<12>
J 0
(-165 2035);
DISPLAY 0.659574 (-165 2035);
PAINT MONO (-165 2035);
DISPLAY INVISIBLE (-165 2035);
FORCEPROP 1 LASTPIN (-175 2025) BN 12
J 2
(-125 2035);
DISPLAY 0.617021 (-125 2035);
PAINT PINK (-125 2035);
FORCEPROP 2 LAST CDS_LIB mstr_standard
J 2
(-125 2025);
DISPLAY 0.787234 (-125 2025);
PAINT MONO (-125 2025);
DISPLAY INVISIBLE (-125 2025);
FORCEPROP 1 LAST BODY_TYPE PLUMBING
J 2
(-125 1975);
DISPLAY 1.234043 (-125 1975);
PAINT GREEN (-125 1975);
DISPLAY INVISIBLE (-125 1975);
FORCEPROP 1 LAST HDL_TAP TRUE
J 2
(-450 1900);
DISPLAY 1.234043 (-450 1900);
PAINT GREEN (-450 1900);
DISPLAY INVISIBLE (-450 1900);
FORCEPROP 1 LAST PATH I62
J 2
(-123 2025);
DISPLAY 0.872340 (-123 2025);
PAINT GREEN (-123 2025);
DISPLAY INVISIBLE (-123 2025);
FORCEADD TAP..6
R 2
(-125 2075);
FORCEPROP 3 LASTPIN (-175 2075) SIG_NAME M_L_DQ<13>
J 0
(-165 2085);
DISPLAY 0.659574 (-165 2085);
PAINT MONO (-165 2085);
DISPLAY INVISIBLE (-165 2085);
FORCEPROP 1 LASTPIN (-175 2075) BN 13
J 2
(-125 2085);
DISPLAY 0.617021 (-125 2085);
PAINT PINK (-125 2085);
FORCEPROP 2 LAST CDS_LIB mstr_standard
J 2
(-125 2075);
DISPLAY 0.787234 (-125 2075);
PAINT MONO (-125 2075);
DISPLAY INVISIBLE (-125 2075);
FORCEPROP 1 LAST BODY_TYPE PLUMBING
J 2
(-125 2025);
DISPLAY 1.234043 (-125 2025);
PAINT GREEN (-125 2025);
DISPLAY INVISIBLE (-125 2025);
FORCEPROP 1 LAST HDL_TAP TRUE
J 2
(-450 1950);
DISPLAY 1.234043 (-450 1950);
PAINT GREEN (-450 1950);
DISPLAY INVISIBLE (-450 1950);
FORCEPROP 1 LAST PATH I63
J 2
(-123 2075);
DISPLAY 0.872340 (-123 2075);
PAINT GREEN (-123 2075);
DISPLAY INVISIBLE (-123 2075);
FORCEADD TAP..6
R 2
(-125 2225);
FORCEPROP 3 LASTPIN (-175 2225) SIG_NAME M_L_DQ<16>
J 0
(-165 2235);
DISPLAY 0.659574 (-165 2235);
PAINT MONO (-165 2235);
DISPLAY INVISIBLE (-165 2235);
FORCEPROP 1 LASTPIN (-175 2225) BN 16
J 2
(-125 2235);
DISPLAY 0.617021 (-125 2235);
PAINT PINK (-125 2235);
FORCEPROP 2 LAST CDS_LIB mstr_standard
J 2
(-125 2225);
DISPLAY 0.787234 (-125 2225);
PAINT MONO (-125 2225);
DISPLAY INVISIBLE (-125 2225);
FORCEPROP 1 LAST BODY_TYPE PLUMBING
J 2
(-125 2175);
DISPLAY 1.234043 (-125 2175);
PAINT GREEN (-125 2175);
DISPLAY INVISIBLE (-125 2175);
FORCEPROP 1 LAST HDL_TAP TRUE
J 2
(-450 2100);
DISPLAY 1.234043 (-450 2100);
PAINT GREEN (-450 2100);
DISPLAY INVISIBLE (-450 2100);
FORCEPROP 1 LAST PATH I64
J 2
(-123 2225);
DISPLAY 0.872340 (-123 2225);
PAINT GREEN (-123 2225);
DISPLAY INVISIBLE (-123 2225);
FORCEADD TAP..6
R 2
(-125 2175);
FORCEPROP 3 LASTPIN (-175 2175) SIG_NAME M_L_DQ<15>
J 0
(-165 2185);
DISPLAY 0.659574 (-165 2185);
PAINT MONO (-165 2185);
DISPLAY INVISIBLE (-165 2185);
FORCEPROP 1 LASTPIN (-175 2175) BN 15
J 2
(-125 2185);
DISPLAY 0.617021 (-125 2185);
PAINT PINK (-125 2185);
FORCEPROP 2 LAST CDS_LIB mstr_standard
J 2
(-125 2175);
DISPLAY 0.787234 (-125 2175);
PAINT MONO (-125 2175);
DISPLAY INVISIBLE (-125 2175);
FORCEPROP 1 LAST BODY_TYPE PLUMBING
J 2
(-125 2125);
DISPLAY 1.234043 (-125 2125);
PAINT GREEN (-125 2125);
DISPLAY INVISIBLE (-125 2125);
FORCEPROP 1 LAST HDL_TAP TRUE
J 2
(-450 2050);
DISPLAY 1.234043 (-450 2050);
PAINT GREEN (-450 2050);
DISPLAY INVISIBLE (-450 2050);
FORCEPROP 1 LAST PATH I65
J 2
(-123 2175);
DISPLAY 0.872340 (-123 2175);
PAINT GREEN (-123 2175);
DISPLAY INVISIBLE (-123 2175);
FORCEADD TAP..6
R 2
(-125 2125);
FORCEPROP 3 LASTPIN (-175 2125) SIG_NAME M_L_DQ<14>
J 0
(-165 2135);
DISPLAY 0.659574 (-165 2135);
PAINT MONO (-165 2135);
DISPLAY INVISIBLE (-165 2135);
FORCEPROP 1 LASTPIN (-175 2125) BN 14
J 2
(-125 2135);
DISPLAY 0.617021 (-125 2135);
PAINT PINK (-125 2135);
FORCEPROP 2 LAST CDS_LIB mstr_standard
J 2
(-125 2125);
DISPLAY 0.787234 (-125 2125);
PAINT MONO (-125 2125);
DISPLAY INVISIBLE (-125 2125);
FORCEPROP 1 LAST BODY_TYPE PLUMBING
J 2
(-125 2075);
DISPLAY 1.234043 (-125 2075);
PAINT GREEN (-125 2075);
DISPLAY INVISIBLE (-125 2075);
FORCEPROP 1 LAST HDL_TAP TRUE
J 2
(-450 2000);
DISPLAY 1.234043 (-450 2000);
PAINT GREEN (-450 2000);
DISPLAY INVISIBLE (-450 2000);
FORCEPROP 1 LAST PATH I66
J 2
(-123 2125);
DISPLAY 0.872340 (-123 2125);
PAINT GREEN (-123 2125);
DISPLAY INVISIBLE (-123 2125);
FORCEADD TAP..6
R 2
(-125 2325);
FORCEPROP 3 LASTPIN (-175 2325) SIG_NAME M_L_DQ<18>
J 0
(-165 2335);
DISPLAY 0.659574 (-165 2335);
PAINT MONO (-165 2335);
DISPLAY INVISIBLE (-165 2335);
FORCEPROP 1 LASTPIN (-175 2325) BN 18
J 2
(-125 2335);
DISPLAY 0.617021 (-125 2335);
PAINT PINK (-125 2335);
FORCEPROP 2 LAST CDS_LIB mstr_standard
J 2
(-125 2325);
DISPLAY 0.787234 (-125 2325);
PAINT MONO (-125 2325);
DISPLAY INVISIBLE (-125 2325);
FORCEPROP 1 LAST BODY_TYPE PLUMBING
J 2
(-125 2275);
DISPLAY 1.234043 (-125 2275);
PAINT GREEN (-125 2275);
DISPLAY INVISIBLE (-125 2275);
FORCEPROP 1 LAST HDL_TAP TRUE
J 2
(-450 2200);
DISPLAY 1.234043 (-450 2200);
PAINT GREEN (-450 2200);
DISPLAY INVISIBLE (-450 2200);
FORCEPROP 1 LAST PATH I67
J 2
(-123 2325);
DISPLAY 0.872340 (-123 2325);
PAINT GREEN (-123 2325);
DISPLAY INVISIBLE (-123 2325);
FORCEADD TAP..6
R 2
(-125 2275);
FORCEPROP 3 LASTPIN (-175 2275) SIG_NAME M_L_DQ<17>
J 0
(-165 2285);
DISPLAY 0.659574 (-165 2285);
PAINT MONO (-165 2285);
DISPLAY INVISIBLE (-165 2285);
FORCEPROP 1 LASTPIN (-175 2275) BN 17
J 2
(-125 2285);
DISPLAY 0.617021 (-125 2285);
PAINT PINK (-125 2285);
FORCEPROP 2 LAST CDS_LIB mstr_standard
J 2
(-125 2275);
DISPLAY 0.787234 (-125 2275);
PAINT MONO (-125 2275);
DISPLAY INVISIBLE (-125 2275);
FORCEPROP 1 LAST BODY_TYPE PLUMBING
J 2
(-125 2225);
DISPLAY 1.234043 (-125 2225);
PAINT GREEN (-125 2225);
DISPLAY INVISIBLE (-125 2225);
FORCEPROP 1 LAST HDL_TAP TRUE
J 2
(-450 2150);
DISPLAY 1.234043 (-450 2150);
PAINT GREEN (-450 2150);
DISPLAY INVISIBLE (-450 2150);
FORCEPROP 1 LAST PATH I68
J 2
(-123 2275);
DISPLAY 0.872340 (-123 2275);
PAINT GREEN (-123 2275);
DISPLAY INVISIBLE (-123 2275);
FORCEADD TAP..6
R 2
(-125 2475);
FORCEPROP 3 LASTPIN (-175 2475) SIG_NAME M_L_DQ<21>
J 0
(-165 2485);
DISPLAY 0.659574 (-165 2485);
PAINT MONO (-165 2485);
DISPLAY INVISIBLE (-165 2485);
FORCEPROP 1 LASTPIN (-175 2475) BN 21
J 2
(-125 2485);
DISPLAY 0.617021 (-125 2485);
PAINT PINK (-125 2485);
FORCEPROP 2 LAST CDS_LIB mstr_standard
J 2
(-125 2475);
DISPLAY 0.787234 (-125 2475);
PAINT MONO (-125 2475);
DISPLAY INVISIBLE (-125 2475);
FORCEPROP 1 LAST BODY_TYPE PLUMBING
J 2
(-125 2425);
DISPLAY 1.234043 (-125 2425);
PAINT GREEN (-125 2425);
DISPLAY INVISIBLE (-125 2425);
FORCEPROP 1 LAST HDL_TAP TRUE
J 2
(-450 2350);
DISPLAY 1.234043 (-450 2350);
PAINT GREEN (-450 2350);
DISPLAY INVISIBLE (-450 2350);
FORCEPROP 1 LAST PATH I69
J 2
(-123 2475);
DISPLAY 0.872340 (-123 2475);
PAINT GREEN (-123 2475);
DISPLAY INVISIBLE (-123 2475);
FORCEADD OFFPAGE..1
(-2425 1875);
FORCEPROP 2 LAST $XR0 61 
J 0
(-2676 1875);
DISPLAY 0.638298 (-2676 1875);
PAINT MONO (-2676 1875);
FORCEPROP 2 LAST $XR1 85 
J 0
(-2766 1875);
DISPLAY 0.638298 (-2766 1875);
PAINT MONO (-2766 1875);
FORCEPROP 2 LAST CDS_LIB mstr_standard
J 0
(-2425 1875);
DISPLAY 0.787234 (-2425 1875);
PAINT MONO (-2425 1875);
DISPLAY INVISIBLE (-2425 1875);
FORCEPROP 1 LAST OFFPAGE TRUE
J 0
(-2100 1750);
DISPLAY 0.936170 (-2100 1750);
PAINT GREEN (-2100 1750);
DISPLAY INVISIBLE (-2100 1750);
FORCEPROP 1 LAST COMMENT_BODY TRUE
J 0
(-2300 1775);
DISPLAY 0.936170 (-2300 1775);
PAINT GREEN (-2300 1775);
DISPLAY INVISIBLE (-2300 1775);
FORCEPROP 2 LAST PATH I7
J 0
(-2675 1925);
DISPLAY 1.021277 (-2675 1925);
PAINT ORANGE (-2675 1925);
DISPLAY INVISIBLE (-2675 1925);
FORCEADD TAP..6
R 2
(-125 2425);
FORCEPROP 3 LASTPIN (-175 2425) SIG_NAME M_L_DQ<20>
J 0
(-165 2435);
DISPLAY 0.659574 (-165 2435);
PAINT MONO (-165 2435);
DISPLAY INVISIBLE (-165 2435);
FORCEPROP 1 LASTPIN (-175 2425) BN 20
J 2
(-125 2435);
DISPLAY 0.617021 (-125 2435);
PAINT PINK (-125 2435);
FORCEPROP 2 LAST CDS_LIB mstr_standard
J 2
(-125 2425);
DISPLAY 0.787234 (-125 2425);
PAINT MONO (-125 2425);
DISPLAY INVISIBLE (-125 2425);
FORCEPROP 1 LAST BODY_TYPE PLUMBING
J 2
(-125 2375);
DISPLAY 1.234043 (-125 2375);
PAINT GREEN (-125 2375);
DISPLAY INVISIBLE (-125 2375);
FORCEPROP 1 LAST HDL_TAP TRUE
J 2
(-450 2300);
DISPLAY 1.234043 (-450 2300);
PAINT GREEN (-450 2300);
DISPLAY INVISIBLE (-450 2300);
FORCEPROP 1 LAST PATH I70
J 2
(-123 2425);
DISPLAY 0.872340 (-123 2425);
PAINT GREEN (-123 2425);
DISPLAY INVISIBLE (-123 2425);
FORCEADD TAP..6
R 2
(-125 2375);
FORCEPROP 3 LASTPIN (-175 2375) SIG_NAME M_L_DQ<19>
J 0
(-165 2385);
DISPLAY 0.659574 (-165 2385);
PAINT MONO (-165 2385);
DISPLAY INVISIBLE (-165 2385);
FORCEPROP 1 LASTPIN (-175 2375) BN 19
J 2
(-125 2385);
DISPLAY 0.617021 (-125 2385);
PAINT PINK (-125 2385);
FORCEPROP 2 LAST CDS_LIB mstr_standard
J 2
(-125 2375);
DISPLAY 0.787234 (-125 2375);
PAINT MONO (-125 2375);
DISPLAY INVISIBLE (-125 2375);
FORCEPROP 1 LAST BODY_TYPE PLUMBING
J 2
(-125 2325);
DISPLAY 1.234043 (-125 2325);
PAINT GREEN (-125 2325);
DISPLAY INVISIBLE (-125 2325);
FORCEPROP 1 LAST HDL_TAP TRUE
J 2
(-450 2250);
DISPLAY 1.234043 (-450 2250);
PAINT GREEN (-450 2250);
DISPLAY INVISIBLE (-450 2250);
FORCEPROP 1 LAST PATH I71
J 2
(-123 2375);
DISPLAY 0.872340 (-123 2375);
PAINT GREEN (-123 2375);
DISPLAY INVISIBLE (-123 2375);
FORCEADD TAP..6
R 2
(-125 2675);
FORCEPROP 3 LASTPIN (-175 2675) SIG_NAME M_L_DQ<25>
J 0
(-165 2685);
DISPLAY 0.659574 (-165 2685);
PAINT MONO (-165 2685);
DISPLAY INVISIBLE (-165 2685);
FORCEPROP 1 LASTPIN (-175 2675) BN 25
J 2
(-125 2685);
DISPLAY 0.617021 (-125 2685);
PAINT PINK (-125 2685);
FORCEPROP 2 LAST CDS_LIB mstr_standard
J 2
(-125 2675);
DISPLAY 0.787234 (-125 2675);
PAINT MONO (-125 2675);
DISPLAY INVISIBLE (-125 2675);
FORCEPROP 1 LAST BODY_TYPE PLUMBING
J 2
(-125 2625);
DISPLAY 1.234043 (-125 2625);
PAINT GREEN (-125 2625);
DISPLAY INVISIBLE (-125 2625);
FORCEPROP 1 LAST HDL_TAP TRUE
J 2
(-450 2550);
DISPLAY 1.234043 (-450 2550);
PAINT GREEN (-450 2550);
DISPLAY INVISIBLE (-450 2550);
FORCEPROP 1 LAST PATH I72
J 2
(-123 2675);
DISPLAY 0.872340 (-123 2675);
PAINT GREEN (-123 2675);
DISPLAY INVISIBLE (-123 2675);
FORCEADD TAP..6
R 2
(-125 2625);
FORCEPROP 3 LASTPIN (-175 2625) SIG_NAME M_L_DQ<24>
J 0
(-165 2635);
DISPLAY 0.659574 (-165 2635);
PAINT MONO (-165 2635);
DISPLAY INVISIBLE (-165 2635);
FORCEPROP 1 LASTPIN (-175 2625) BN 24
J 2
(-125 2635);
DISPLAY 0.617021 (-125 2635);
PAINT PINK (-125 2635);
FORCEPROP 2 LAST CDS_LIB mstr_standard
J 2
(-125 2625);
DISPLAY 0.787234 (-125 2625);
PAINT MONO (-125 2625);
DISPLAY INVISIBLE (-125 2625);
FORCEPROP 1 LAST BODY_TYPE PLUMBING
J 2
(-125 2575);
DISPLAY 1.234043 (-125 2575);
PAINT GREEN (-125 2575);
DISPLAY INVISIBLE (-125 2575);
FORCEPROP 1 LAST HDL_TAP TRUE
J 2
(-450 2500);
DISPLAY 1.234043 (-450 2500);
PAINT GREEN (-450 2500);
DISPLAY INVISIBLE (-450 2500);
FORCEPROP 1 LAST PATH I73
J 2
(-123 2625);
DISPLAY 0.872340 (-123 2625);
PAINT GREEN (-123 2625);
DISPLAY INVISIBLE (-123 2625);
FORCEADD TAP..6
R 2
(-125 2725);
FORCEPROP 3 LASTPIN (-175 2725) SIG_NAME M_L_DQ<26>
J 0
(-165 2735);
DISPLAY 0.659574 (-165 2735);
PAINT MONO (-165 2735);
DISPLAY INVISIBLE (-165 2735);
FORCEPROP 1 LASTPIN (-175 2725) BN 26
J 2
(-125 2735);
DISPLAY 0.617021 (-125 2735);
PAINT PINK (-125 2735);
FORCEPROP 2 LAST CDS_LIB mstr_standard
J 2
(-125 2725);
DISPLAY 0.787234 (-125 2725);
PAINT MONO (-125 2725);
DISPLAY INVISIBLE (-125 2725);
FORCEPROP 1 LAST BODY_TYPE PLUMBING
J 2
(-125 2675);
DISPLAY 1.234043 (-125 2675);
PAINT GREEN (-125 2675);
DISPLAY INVISIBLE (-125 2675);
FORCEPROP 1 LAST HDL_TAP TRUE
J 2
(-450 2600);
DISPLAY 1.234043 (-450 2600);
PAINT GREEN (-450 2600);
DISPLAY INVISIBLE (-450 2600);
FORCEPROP 1 LAST PATH I74
J 2
(-123 2725);
DISPLAY 0.872340 (-123 2725);
PAINT GREEN (-123 2725);
DISPLAY INVISIBLE (-123 2725);
FORCEADD TAP..6
R 2
(-125 2525);
FORCEPROP 3 LASTPIN (-175 2525) SIG_NAME M_L_DQ<22>
J 0
(-165 2535);
DISPLAY 0.659574 (-165 2535);
PAINT MONO (-165 2535);
DISPLAY INVISIBLE (-165 2535);
FORCEPROP 1 LASTPIN (-175 2525) BN 22
J 2
(-125 2535);
DISPLAY 0.617021 (-125 2535);
PAINT PINK (-125 2535);
FORCEPROP 2 LAST CDS_LIB mstr_standard
J 2
(-125 2525);
DISPLAY 0.787234 (-125 2525);
PAINT MONO (-125 2525);
DISPLAY INVISIBLE (-125 2525);
FORCEPROP 1 LAST BODY_TYPE PLUMBING
J 2
(-125 2475);
DISPLAY 1.234043 (-125 2475);
PAINT GREEN (-125 2475);
DISPLAY INVISIBLE (-125 2475);
FORCEPROP 1 LAST HDL_TAP TRUE
J 2
(-450 2400);
DISPLAY 1.234043 (-450 2400);
PAINT GREEN (-450 2400);
DISPLAY INVISIBLE (-450 2400);
FORCEPROP 1 LAST PATH I75
J 2
(-123 2525);
DISPLAY 0.872340 (-123 2525);
PAINT GREEN (-123 2525);
DISPLAY INVISIBLE (-123 2525);
FORCEADD TAP..6
R 2
(-125 2575);
FORCEPROP 3 LASTPIN (-175 2575) SIG_NAME M_L_DQ<23>
J 0
(-165 2585);
DISPLAY 0.659574 (-165 2585);
PAINT MONO (-165 2585);
DISPLAY INVISIBLE (-165 2585);
FORCEPROP 1 LASTPIN (-175 2575) BN 23
J 2
(-125 2585);
DISPLAY 0.617021 (-125 2585);
PAINT PINK (-125 2585);
FORCEPROP 2 LAST CDS_LIB mstr_standard
J 2
(-125 2575);
DISPLAY 0.787234 (-125 2575);
PAINT MONO (-125 2575);
DISPLAY INVISIBLE (-125 2575);
FORCEPROP 1 LAST BODY_TYPE PLUMBING
J 2
(-125 2525);
DISPLAY 1.234043 (-125 2525);
PAINT GREEN (-125 2525);
DISPLAY INVISIBLE (-125 2525);
FORCEPROP 1 LAST HDL_TAP TRUE
J 2
(-450 2450);
DISPLAY 1.234043 (-450 2450);
PAINT GREEN (-450 2450);
DISPLAY INVISIBLE (-450 2450);
FORCEPROP 1 LAST PATH I76
J 2
(-123 2575);
DISPLAY 0.872340 (-123 2575);
PAINT GREEN (-123 2575);
DISPLAY INVISIBLE (-123 2575);
FORCEADD PVDDQ_KLM..1
(275 2275);
FORCEPROP 3 LASTPIN (275 2225) SIG_NAME PVDDQ_KLM\g
J 0
(285 2235);
DISPLAY 0.659574 (285 2235);
PAINT MONO (285 2235);
DISPLAY INVISIBLE (285 2235);
FORCEPROP 1 LAST VOLTAGE 1.2V
J 0
(230 2232);
DISPLAY 0.340426 (230 2232);
PAINT SKYBLUE (230 2232);
DISPLAY INVISIBLE (230 2232);
FORCEPROP 2 LAST BOM_COST MEM
J 0
(275 2280);
PAINT ORANGE (275 2280);
DISPLAY INVISIBLE (275 2280);
FORCEPROP 2 LAST CDS_LIB mstr_symbols
J 0
(275 2275);
PAINT ORANGE (275 2275);
DISPLAY INVISIBLE (275 2275);
FORCEPROP 1 LAST BODY_TYPE PLUMBING
J 0
(230 2232);
DISPLAY 0.340426 (230 2232);
PAINT GREEN (230 2232);
DISPLAY INVISIBLE (230 2232);
FORCEPROP 1 LAST PATH I77
J 0
(325 2300);
DISPLAY 0.872340 (325 2300);
PAINT AQUA (325 2300);
DISPLAY INVISIBLE (325 2300);
FORCEPROP 2 LAST ROOM DDR4_CH_D
J 0
(275 2375);
DISPLAY 0.787234 (275 2375);
PAINT ORANGE (275 2375);
DISPLAY INVISIBLE (275 2375);
FORCEPROP 1 LAST HDL_POWER PVDDQ_KLM
J 1
(275 2325);
DISPLAY 0.872340 (275 2325);
PAINT GREEN (275 2325);
DISPLAY INVISIBLE (275 2325);
FORCEADD PVTT_KLM..1
(525 2425);
FORCEPROP 3 LASTPIN (525 2375) SIG_NAME PVTT_KLM\g
J 0
(535 2385);
DISPLAY 0.659574 (535 2385);
PAINT MONO (535 2385);
DISPLAY INVISIBLE (535 2385);
FORCEPROP 1 LAST VOLTAGE 0.6V
J 0
(480 2382);
DISPLAY 0.340426 (480 2382);
PAINT SKYBLUE (480 2382);
DISPLAY INVISIBLE (480 2382);
FORCEPROP 2 LAST BOM_COST MEM
J 0
(525 2430);
PAINT ORANGE (525 2430);
DISPLAY INVISIBLE (525 2430);
FORCEPROP 2 LAST CDS_LIB mstr_symbols
J 0
(525 2425);
PAINT ORANGE (525 2425);
DISPLAY INVISIBLE (525 2425);
FORCEPROP 1 LAST BODY_TYPE PLUMBING
J 0
(480 2382);
DISPLAY 0.340426 (480 2382);
PAINT GREEN (480 2382);
DISPLAY INVISIBLE (480 2382);
FORCEPROP 1 LAST PATH I78
J 0
(575 2450);
DISPLAY 0.872340 (575 2450);
PAINT AQUA (575 2450);
DISPLAY INVISIBLE (575 2450);
FORCEPROP 2 LAST ROOM DDR4_CH_D
J 0
(525 2525);
DISPLAY 0.787234 (525 2525);
PAINT ORANGE (525 2525);
DISPLAY INVISIBLE (525 2525);
FORCEPROP 1 LAST HDL_POWER PVTT_KLM
J 1
(525 2475);
DISPLAY 0.872340 (525 2475);
PAINT GREEN (525 2475);
DISPLAY INVISIBLE (525 2475);
FORCEADD TAP..6
R 2
(-125 2775);
FORCEPROP 3 LASTPIN (-175 2775) SIG_NAME M_L_DQ<27>
J 0
(-165 2785);
DISPLAY 0.659574 (-165 2785);
PAINT MONO (-165 2785);
DISPLAY INVISIBLE (-165 2785);
FORCEPROP 1 LASTPIN (-175 2775) BN 27
J 2
(-125 2785);
DISPLAY 0.617021 (-125 2785);
PAINT PINK (-125 2785);
FORCEPROP 2 LAST CDS_LIB mstr_standard
J 2
(-125 2775);
DISPLAY 0.787234 (-125 2775);
PAINT MONO (-125 2775);
DISPLAY INVISIBLE (-125 2775);
FORCEPROP 1 LAST BODY_TYPE PLUMBING
J 2
(-125 2725);
DISPLAY 1.234043 (-125 2725);
PAINT GREEN (-125 2725);
DISPLAY INVISIBLE (-125 2725);
FORCEPROP 1 LAST HDL_TAP TRUE
J 2
(-450 2650);
DISPLAY 1.234043 (-450 2650);
PAINT GREEN (-450 2650);
DISPLAY INVISIBLE (-450 2650);
FORCEPROP 1 LAST PATH I79
J 2
(-123 2775);
DISPLAY 0.872340 (-123 2775);
PAINT GREEN (-123 2775);
DISPLAY INVISIBLE (-123 2775);
FORCEADD OFFPAGE..5
(-2450 1925);
FORCEPROP 2 LAST $XR0 85 
J 0
(-2674 1925);
DISPLAY 0.638298 (-2674 1925);
PAINT MONO (-2674 1925);
FORCEPROP 2 LAST $XR1 61 
J 0
(-2764 1925);
DISPLAY 0.638298 (-2764 1925);
PAINT MONO (-2764 1925);
FORCEPROP 2 LAST CDS_LIB mstr_standard
J 0
(-2450 1925);
DISPLAY 0.787234 (-2450 1925);
PAINT MONO (-2450 1925);
DISPLAY INVISIBLE (-2450 1925);
FORCEPROP 1 LAST OFFPAGE TRUE
J 0
(-2125 1800);
DISPLAY 1.404255 (-2125 1800);
PAINT GREEN (-2125 1800);
DISPLAY INVISIBLE (-2125 1800);
FORCEPROP 1 LAST COMMENT_BODY TRUE
J 0
(-2350 1850);
DISPLAY 1.404255 (-2350 1850);
PAINT GREEN (-2350 1850);
DISPLAY INVISIBLE (-2350 1850);
FORCEPROP 2 LAST PATH I8
J 0
(-2650 1975);
DISPLAY 1.021277 (-2650 1975);
PAINT ORANGE (-2650 1975);
DISPLAY INVISIBLE (-2650 1975);
FORCEADD TAP..6
R 2
(-125 2825);
FORCEPROP 3 LASTPIN (-175 2825) SIG_NAME M_L_DQ<28>
J 0
(-165 2835);
DISPLAY 0.659574 (-165 2835);
PAINT MONO (-165 2835);
DISPLAY INVISIBLE (-165 2835);
FORCEPROP 1 LASTPIN (-175 2825) BN 28
J 2
(-125 2835);
DISPLAY 0.617021 (-125 2835);
PAINT PINK (-125 2835);
FORCEPROP 2 LAST CDS_LIB mstr_standard
J 2
(-125 2825);
DISPLAY 0.787234 (-125 2825);
PAINT MONO (-125 2825);
DISPLAY INVISIBLE (-125 2825);
FORCEPROP 1 LAST BODY_TYPE PLUMBING
J 2
(-125 2775);
DISPLAY 1.234043 (-125 2775);
PAINT GREEN (-125 2775);
DISPLAY INVISIBLE (-125 2775);
FORCEPROP 1 LAST HDL_TAP TRUE
J 2
(-450 2700);
DISPLAY 1.234043 (-450 2700);
PAINT GREEN (-450 2700);
DISPLAY INVISIBLE (-450 2700);
FORCEPROP 1 LAST PATH I80
J 2
(-123 2825);
DISPLAY 0.872340 (-123 2825);
PAINT GREEN (-123 2825);
DISPLAY INVISIBLE (-123 2825);
FORCEADD TAP..6
R 2
(-125 2875);
FORCEPROP 3 LASTPIN (-175 2875) SIG_NAME M_L_DQ<29>
J 0
(-165 2885);
DISPLAY 0.659574 (-165 2885);
PAINT MONO (-165 2885);
DISPLAY INVISIBLE (-165 2885);
FORCEPROP 1 LASTPIN (-175 2875) BN 29
J 2
(-125 2885);
DISPLAY 0.617021 (-125 2885);
PAINT PINK (-125 2885);
FORCEPROP 2 LAST CDS_LIB mstr_standard
J 2
(-125 2875);
DISPLAY 0.787234 (-125 2875);
PAINT MONO (-125 2875);
DISPLAY INVISIBLE (-125 2875);
FORCEPROP 1 LAST BODY_TYPE PLUMBING
J 2
(-125 2825);
DISPLAY 1.234043 (-125 2825);
PAINT GREEN (-125 2825);
DISPLAY INVISIBLE (-125 2825);
FORCEPROP 1 LAST HDL_TAP TRUE
J 2
(-450 2750);
DISPLAY 1.234043 (-450 2750);
PAINT GREEN (-450 2750);
DISPLAY INVISIBLE (-450 2750);
FORCEPROP 1 LAST PATH I81
J 2
(-123 2875);
DISPLAY 0.872340 (-123 2875);
PAINT GREEN (-123 2875);
DISPLAY INVISIBLE (-123 2875);
FORCEADD TAP..6
R 2
(-125 2975);
FORCEPROP 3 LASTPIN (-175 2975) SIG_NAME M_L_DQ<31>
J 0
(-165 2985);
DISPLAY 0.659574 (-165 2985);
PAINT MONO (-165 2985);
DISPLAY INVISIBLE (-165 2985);
FORCEPROP 1 LASTPIN (-175 2975) BN 31
J 2
(-125 2985);
DISPLAY 0.617021 (-125 2985);
PAINT PINK (-125 2985);
FORCEPROP 2 LAST CDS_LIB mstr_standard
J 2
(-125 2975);
DISPLAY 0.787234 (-125 2975);
PAINT MONO (-125 2975);
DISPLAY INVISIBLE (-125 2975);
FORCEPROP 1 LAST BODY_TYPE PLUMBING
J 2
(-125 2925);
DISPLAY 1.234043 (-125 2925);
PAINT GREEN (-125 2925);
DISPLAY INVISIBLE (-125 2925);
FORCEPROP 1 LAST HDL_TAP TRUE
J 2
(-450 2850);
DISPLAY 1.234043 (-450 2850);
PAINT GREEN (-450 2850);
DISPLAY INVISIBLE (-450 2850);
FORCEPROP 1 LAST PATH I82
J 2
(-123 2975);
DISPLAY 0.872340 (-123 2975);
PAINT GREEN (-123 2975);
DISPLAY INVISIBLE (-123 2975);
FORCEADD TAP..6
R 2
(-125 2925);
FORCEPROP 3 LASTPIN (-175 2925) SIG_NAME M_L_DQ<30>
J 0
(-165 2935);
DISPLAY 0.659574 (-165 2935);
PAINT MONO (-165 2935);
DISPLAY INVISIBLE (-165 2935);
FORCEPROP 1 LASTPIN (-175 2925) BN 30
J 2
(-125 2935);
DISPLAY 0.617021 (-125 2935);
PAINT PINK (-125 2935);
FORCEPROP 2 LAST CDS_LIB mstr_standard
J 2
(-125 2925);
DISPLAY 0.787234 (-125 2925);
PAINT MONO (-125 2925);
DISPLAY INVISIBLE (-125 2925);
FORCEPROP 1 LAST BODY_TYPE PLUMBING
J 2
(-125 2875);
DISPLAY 1.234043 (-125 2875);
PAINT GREEN (-125 2875);
DISPLAY INVISIBLE (-125 2875);
FORCEPROP 1 LAST HDL_TAP TRUE
J 2
(-450 2800);
DISPLAY 1.234043 (-450 2800);
PAINT GREEN (-450 2800);
DISPLAY INVISIBLE (-450 2800);
FORCEPROP 1 LAST PATH I83
J 2
(-123 2925);
DISPLAY 0.872340 (-123 2925);
PAINT GREEN (-123 2925);
DISPLAY INVISIBLE (-123 2925);
FORCEADD TAP..6
R 2
(-125 3175);
FORCEPROP 3 LASTPIN (-175 3175) SIG_NAME M_L_DQ<35>
J 0
(-165 3185);
DISPLAY 0.659574 (-165 3185);
PAINT MONO (-165 3185);
DISPLAY INVISIBLE (-165 3185);
FORCEPROP 1 LASTPIN (-175 3175) BN 35
J 2
(-125 3185);
DISPLAY 0.617021 (-125 3185);
PAINT PINK (-125 3185);
FORCEPROP 2 LAST CDS_LIB mstr_standard
J 2
(-125 3175);
DISPLAY 0.787234 (-125 3175);
PAINT MONO (-125 3175);
DISPLAY INVISIBLE (-125 3175);
FORCEPROP 1 LAST BODY_TYPE PLUMBING
J 2
(-125 3125);
DISPLAY 1.234043 (-125 3125);
PAINT GREEN (-125 3125);
DISPLAY INVISIBLE (-125 3125);
FORCEPROP 1 LAST HDL_TAP TRUE
J 2
(-450 3050);
DISPLAY 1.234043 (-450 3050);
PAINT GREEN (-450 3050);
DISPLAY INVISIBLE (-450 3050);
FORCEPROP 1 LAST PATH I84
J 2
(-123 3175);
DISPLAY 0.872340 (-123 3175);
PAINT GREEN (-123 3175);
DISPLAY INVISIBLE (-123 3175);
FORCEADD TAP..6
R 2
(-125 3125);
FORCEPROP 3 LASTPIN (-175 3125) SIG_NAME M_L_DQ<34>
J 0
(-165 3135);
DISPLAY 0.659574 (-165 3135);
PAINT MONO (-165 3135);
DISPLAY INVISIBLE (-165 3135);
FORCEPROP 1 LASTPIN (-175 3125) BN 34
J 2
(-125 3135);
DISPLAY 0.617021 (-125 3135);
PAINT PINK (-125 3135);
FORCEPROP 2 LAST CDS_LIB mstr_standard
J 2
(-125 3125);
DISPLAY 0.787234 (-125 3125);
PAINT MONO (-125 3125);
DISPLAY INVISIBLE (-125 3125);
FORCEPROP 1 LAST BODY_TYPE PLUMBING
J 2
(-125 3075);
DISPLAY 1.234043 (-125 3075);
PAINT GREEN (-125 3075);
DISPLAY INVISIBLE (-125 3075);
FORCEPROP 1 LAST HDL_TAP TRUE
J 2
(-450 3000);
DISPLAY 1.234043 (-450 3000);
PAINT GREEN (-450 3000);
DISPLAY INVISIBLE (-450 3000);
FORCEPROP 1 LAST PATH I85
J 2
(-123 3125);
DISPLAY 0.872340 (-123 3125);
PAINT GREEN (-123 3125);
DISPLAY INVISIBLE (-123 3125);
FORCEADD TAP..6
R 2
(-125 3225);
FORCEPROP 3 LASTPIN (-175 3225) SIG_NAME M_L_DQ<36>
J 0
(-165 3235);
DISPLAY 0.659574 (-165 3235);
PAINT MONO (-165 3235);
DISPLAY INVISIBLE (-165 3235);
FORCEPROP 1 LASTPIN (-175 3225) BN 36
J 2
(-125 3235);
DISPLAY 0.617021 (-125 3235);
PAINT PINK (-125 3235);
FORCEPROP 2 LAST CDS_LIB mstr_standard
J 2
(-125 3225);
DISPLAY 0.787234 (-125 3225);
PAINT MONO (-125 3225);
DISPLAY INVISIBLE (-125 3225);
FORCEPROP 1 LAST BODY_TYPE PLUMBING
J 2
(-125 3175);
DISPLAY 1.234043 (-125 3175);
PAINT GREEN (-125 3175);
DISPLAY INVISIBLE (-125 3175);
FORCEPROP 1 LAST HDL_TAP TRUE
J 2
(-450 3100);
DISPLAY 1.234043 (-450 3100);
PAINT GREEN (-450 3100);
DISPLAY INVISIBLE (-450 3100);
FORCEPROP 1 LAST PATH I86
J 2
(-123 3225);
DISPLAY 0.872340 (-123 3225);
PAINT GREEN (-123 3225);
DISPLAY INVISIBLE (-123 3225);
FORCEADD TAP..6
R 2
(-125 3075);
FORCEPROP 3 LASTPIN (-175 3075) SIG_NAME M_L_DQ<33>
J 0
(-165 3085);
DISPLAY 0.659574 (-165 3085);
PAINT MONO (-165 3085);
DISPLAY INVISIBLE (-165 3085);
FORCEPROP 1 LASTPIN (-175 3075) BN 33
J 2
(-125 3085);
DISPLAY 0.617021 (-125 3085);
PAINT PINK (-125 3085);
FORCEPROP 2 LAST CDS_LIB mstr_standard
J 2
(-125 3075);
DISPLAY 0.787234 (-125 3075);
PAINT MONO (-125 3075);
DISPLAY INVISIBLE (-125 3075);
FORCEPROP 1 LAST BODY_TYPE PLUMBING
J 2
(-125 3025);
DISPLAY 1.234043 (-125 3025);
PAINT GREEN (-125 3025);
DISPLAY INVISIBLE (-125 3025);
FORCEPROP 1 LAST HDL_TAP TRUE
J 2
(-450 2950);
DISPLAY 1.234043 (-450 2950);
PAINT GREEN (-450 2950);
DISPLAY INVISIBLE (-450 2950);
FORCEPROP 1 LAST PATH I87
J 2
(-123 3075);
DISPLAY 0.872340 (-123 3075);
PAINT GREEN (-123 3075);
DISPLAY INVISIBLE (-123 3075);
FORCEADD TAP..6
R 2
(-125 3025);
FORCEPROP 3 LASTPIN (-175 3025) SIG_NAME M_L_DQ<32>
J 0
(-165 3035);
DISPLAY 0.659574 (-165 3035);
PAINT MONO (-165 3035);
DISPLAY INVISIBLE (-165 3035);
FORCEPROP 1 LASTPIN (-175 3025) BN 32
J 2
(-125 3035);
DISPLAY 0.617021 (-125 3035);
PAINT PINK (-125 3035);
FORCEPROP 2 LAST CDS_LIB mstr_standard
J 2
(-125 3025);
DISPLAY 0.787234 (-125 3025);
PAINT MONO (-125 3025);
DISPLAY INVISIBLE (-125 3025);
FORCEPROP 1 LAST BODY_TYPE PLUMBING
J 2
(-125 2975);
DISPLAY 1.234043 (-125 2975);
PAINT GREEN (-125 2975);
DISPLAY INVISIBLE (-125 2975);
FORCEPROP 1 LAST HDL_TAP TRUE
J 2
(-450 2900);
DISPLAY 1.234043 (-450 2900);
PAINT GREEN (-450 2900);
DISPLAY INVISIBLE (-450 2900);
FORCEPROP 1 LAST PATH I88
J 2
(-123 3025);
DISPLAY 0.872340 (-123 3025);
PAINT GREEN (-123 3025);
DISPLAY INVISIBLE (-123 3025);
FORCEADD TAP..6
R 2
(-125 3325);
FORCEPROP 3 LASTPIN (-175 3325) SIG_NAME M_L_DQ<38>
J 0
(-165 3335);
DISPLAY 0.659574 (-165 3335);
PAINT MONO (-165 3335);
DISPLAY INVISIBLE (-165 3335);
FORCEPROP 1 LASTPIN (-175 3325) BN 38
J 2
(-125 3335);
DISPLAY 0.617021 (-125 3335);
PAINT PINK (-125 3335);
FORCEPROP 2 LAST CDS_LIB mstr_standard
J 2
(-125 3325);
DISPLAY 0.787234 (-125 3325);
PAINT MONO (-125 3325);
DISPLAY INVISIBLE (-125 3325);
FORCEPROP 1 LAST BODY_TYPE PLUMBING
J 2
(-125 3275);
DISPLAY 1.234043 (-125 3275);
PAINT GREEN (-125 3275);
DISPLAY INVISIBLE (-125 3275);
FORCEPROP 1 LAST HDL_TAP TRUE
J 2
(-450 3200);
DISPLAY 1.234043 (-450 3200);
PAINT GREEN (-450 3200);
DISPLAY INVISIBLE (-450 3200);
FORCEPROP 1 LAST PATH I89
J 2
(-123 3325);
DISPLAY 0.872340 (-123 3325);
PAINT GREEN (-123 3325);
DISPLAY INVISIBLE (-123 3325);
FORCEADD OFFPAGE..1
(-2275 1125);
FORCEPROP 2 LAST $XR0 89 
J 0
(-2496 1125);
DISPLAY 0.638298 (-2496 1125);
PAINT MONO (-2496 1125);
FORCEPROP 2 LAST $XR1 83 
J 0
(-2586 1125);
DISPLAY 0.638298 (-2586 1125);
PAINT MONO (-2586 1125);
FORCEPROP 2 LAST $XR2 84 
J 0
(-2676 1125);
DISPLAY 0.638298 (-2676 1125);
PAINT MONO (-2676 1125);
FORCEPROP 2 LAST $XR3 85 
J 0
(-2766 1125);
DISPLAY 0.638298 (-2766 1125);
PAINT MONO (-2766 1125);
FORCEPROP 2 LAST $XR4 87 
J 0
(-2856 1125);
DISPLAY 0.638298 (-2856 1125);
PAINT MONO (-2856 1125);
FORCEPROP 2 LAST $XR5 88 
J 0
(-2946 1125);
DISPLAY 0.638298 (-2946 1125);
PAINT MONO (-2946 1125);
FORCEPROP 2 LAST CDS_LIB mstr_standard
J 0
(-2275 1125);
PAINT ORANGE (-2275 1125);
DISPLAY INVISIBLE (-2275 1125);
FORCEPROP 1 LAST OFFPAGE TRUE
J 0
(-1950 1000);
DISPLAY 0.936170 (-1950 1000);
PAINT GREEN (-1950 1000);
DISPLAY INVISIBLE (-1950 1000);
FORCEPROP 1 LAST COMMENT_BODY TRUE
J 0
(-2150 1025);
DISPLAY 0.936170 (-2150 1025);
PAINT GREEN (-2150 1025);
DISPLAY INVISIBLE (-2150 1025);
FORCEPROP 2 LAST PATH I9
J 0
(-2525 1175);
DISPLAY 1.021277 (-2525 1175);
PAINT ORANGE (-2525 1175);
DISPLAY INVISIBLE (-2525 1175);
FORCEADD TAP..6
R 2
(-125 3275);
FORCEPROP 3 LASTPIN (-175 3275) SIG_NAME M_L_DQ<37>
J 0
(-165 3285);
DISPLAY 0.659574 (-165 3285);
PAINT MONO (-165 3285);
DISPLAY INVISIBLE (-165 3285);
FORCEPROP 1 LASTPIN (-175 3275) BN 37
J 2
(-125 3285);
DISPLAY 0.617021 (-125 3285);
PAINT PINK (-125 3285);
FORCEPROP 2 LAST CDS_LIB mstr_standard
J 2
(-125 3275);
DISPLAY 0.787234 (-125 3275);
PAINT MONO (-125 3275);
DISPLAY INVISIBLE (-125 3275);
FORCEPROP 1 LAST BODY_TYPE PLUMBING
J 2
(-125 3225);
DISPLAY 1.234043 (-125 3225);
PAINT GREEN (-125 3225);
DISPLAY INVISIBLE (-125 3225);
FORCEPROP 1 LAST HDL_TAP TRUE
J 2
(-450 3150);
DISPLAY 1.234043 (-450 3150);
PAINT GREEN (-450 3150);
DISPLAY INVISIBLE (-450 3150);
FORCEPROP 1 LAST PATH I90
J 2
(-123 3275);
DISPLAY 0.872340 (-123 3275);
PAINT GREEN (-123 3275);
DISPLAY INVISIBLE (-123 3275);
FORCEADD TAP..6
R 2
(-125 3425);
FORCEPROP 3 LASTPIN (-175 3425) SIG_NAME M_L_DQ<40>
J 0
(-165 3435);
DISPLAY 0.659574 (-165 3435);
PAINT MONO (-165 3435);
DISPLAY INVISIBLE (-165 3435);
FORCEPROP 1 LASTPIN (-175 3425) BN 40
J 2
(-125 3435);
DISPLAY 0.617021 (-125 3435);
PAINT PINK (-125 3435);
FORCEPROP 2 LAST CDS_LIB mstr_standard
J 2
(-125 3425);
DISPLAY 0.787234 (-125 3425);
PAINT MONO (-125 3425);
DISPLAY INVISIBLE (-125 3425);
FORCEPROP 1 LAST BODY_TYPE PLUMBING
J 2
(-125 3375);
DISPLAY 1.234043 (-125 3375);
PAINT GREEN (-125 3375);
DISPLAY INVISIBLE (-125 3375);
FORCEPROP 1 LAST HDL_TAP TRUE
J 2
(-450 3300);
DISPLAY 1.234043 (-450 3300);
PAINT GREEN (-450 3300);
DISPLAY INVISIBLE (-450 3300);
FORCEPROP 1 LAST PATH I91
J 2
(-123 3425);
DISPLAY 0.872340 (-123 3425);
PAINT GREEN (-123 3425);
DISPLAY INVISIBLE (-123 3425);
FORCEADD TAP..6
R 2
(-125 3375);
FORCEPROP 3 LASTPIN (-175 3375) SIG_NAME M_L_DQ<39>
J 0
(-165 3385);
DISPLAY 0.659574 (-165 3385);
PAINT MONO (-165 3385);
DISPLAY INVISIBLE (-165 3385);
FORCEPROP 1 LASTPIN (-175 3375) BN 39
J 2
(-125 3385);
DISPLAY 0.617021 (-125 3385);
PAINT PINK (-125 3385);
FORCEPROP 2 LAST CDS_LIB mstr_standard
J 2
(-125 3375);
DISPLAY 0.787234 (-125 3375);
PAINT MONO (-125 3375);
DISPLAY INVISIBLE (-125 3375);
FORCEPROP 1 LAST BODY_TYPE PLUMBING
J 2
(-125 3325);
DISPLAY 1.234043 (-125 3325);
PAINT GREEN (-125 3325);
DISPLAY INVISIBLE (-125 3325);
FORCEPROP 1 LAST HDL_TAP TRUE
J 2
(-450 3250);
DISPLAY 1.234043 (-450 3250);
PAINT GREEN (-450 3250);
DISPLAY INVISIBLE (-450 3250);
FORCEPROP 1 LAST PATH I92
J 2
(-123 3375);
DISPLAY 0.872340 (-123 3375);
PAINT GREEN (-123 3375);
DISPLAY INVISIBLE (-123 3375);
FORCEADD TAP..6
R 2
(-125 3475);
FORCEPROP 3 LASTPIN (-175 3475) SIG_NAME M_L_DQ<41>
J 0
(-165 3485);
DISPLAY 0.659574 (-165 3485);
PAINT MONO (-165 3485);
DISPLAY INVISIBLE (-165 3485);
FORCEPROP 1 LASTPIN (-175 3475) BN 41
J 2
(-125 3485);
DISPLAY 0.617021 (-125 3485);
PAINT PINK (-125 3485);
FORCEPROP 2 LAST CDS_LIB mstr_standard
J 2
(-125 3475);
DISPLAY 0.787234 (-125 3475);
PAINT MONO (-125 3475);
DISPLAY INVISIBLE (-125 3475);
FORCEPROP 1 LAST BODY_TYPE PLUMBING
J 2
(-125 3425);
DISPLAY 1.234043 (-125 3425);
PAINT GREEN (-125 3425);
DISPLAY INVISIBLE (-125 3425);
FORCEPROP 1 LAST HDL_TAP TRUE
J 2
(-450 3350);
DISPLAY 1.234043 (-450 3350);
PAINT GREEN (-450 3350);
DISPLAY INVISIBLE (-450 3350);
FORCEPROP 1 LAST PATH I93
J 2
(-123 3475);
DISPLAY 0.872340 (-123 3475);
PAINT GREEN (-123 3475);
DISPLAY INVISIBLE (-123 3475);
FORCEADD TAP..6
R 2
(-125 3625);
FORCEPROP 3 LASTPIN (-175 3625) SIG_NAME M_L_DQ<44>
J 0
(-165 3635);
DISPLAY 0.659574 (-165 3635);
PAINT MONO (-165 3635);
DISPLAY INVISIBLE (-165 3635);
FORCEPROP 1 LASTPIN (-175 3625) BN 44
J 2
(-125 3635);
DISPLAY 0.617021 (-125 3635);
PAINT PINK (-125 3635);
FORCEPROP 2 LAST CDS_LIB mstr_standard
J 2
(-125 3625);
DISPLAY 0.787234 (-125 3625);
PAINT MONO (-125 3625);
DISPLAY INVISIBLE (-125 3625);
FORCEPROP 1 LAST BODY_TYPE PLUMBING
J 2
(-125 3575);
DISPLAY 1.234043 (-125 3575);
PAINT GREEN (-125 3575);
DISPLAY INVISIBLE (-125 3575);
FORCEPROP 1 LAST HDL_TAP TRUE
J 2
(-450 3500);
DISPLAY 1.234043 (-450 3500);
PAINT GREEN (-450 3500);
DISPLAY INVISIBLE (-450 3500);
FORCEPROP 1 LAST PATH I94
J 2
(-123 3625);
DISPLAY 0.872340 (-123 3625);
PAINT GREEN (-123 3625);
DISPLAY INVISIBLE (-123 3625);
FORCEADD TAP..6
R 2
(-125 3675);
FORCEPROP 3 LASTPIN (-175 3675) SIG_NAME M_L_DQ<45>
J 0
(-165 3685);
DISPLAY 0.659574 (-165 3685);
PAINT MONO (-165 3685);
DISPLAY INVISIBLE (-165 3685);
FORCEPROP 1 LASTPIN (-175 3675) BN 45
J 2
(-125 3685);
DISPLAY 0.617021 (-125 3685);
PAINT PINK (-125 3685);
FORCEPROP 2 LAST CDS_LIB mstr_standard
J 2
(-125 3675);
DISPLAY 0.787234 (-125 3675);
PAINT MONO (-125 3675);
DISPLAY INVISIBLE (-125 3675);
FORCEPROP 1 LAST BODY_TYPE PLUMBING
J 2
(-125 3625);
DISPLAY 1.234043 (-125 3625);
PAINT GREEN (-125 3625);
DISPLAY INVISIBLE (-125 3625);
FORCEPROP 1 LAST HDL_TAP TRUE
J 2
(-450 3550);
DISPLAY 1.234043 (-450 3550);
PAINT GREEN (-450 3550);
DISPLAY INVISIBLE (-450 3550);
FORCEPROP 1 LAST PATH I95
J 2
(-123 3675);
DISPLAY 0.872340 (-123 3675);
PAINT GREEN (-123 3675);
DISPLAY INVISIBLE (-123 3675);
FORCEADD TAP..6
R 2
(-125 3725);
FORCEPROP 3 LASTPIN (-175 3725) SIG_NAME M_L_DQ<46>
J 0
(-165 3735);
DISPLAY 0.659574 (-165 3735);
PAINT MONO (-165 3735);
DISPLAY INVISIBLE (-165 3735);
FORCEPROP 1 LASTPIN (-175 3725) BN 46
J 2
(-125 3735);
DISPLAY 0.617021 (-125 3735);
PAINT PINK (-125 3735);
FORCEPROP 2 LAST CDS_LIB mstr_standard
J 2
(-125 3725);
DISPLAY 0.787234 (-125 3725);
PAINT MONO (-125 3725);
DISPLAY INVISIBLE (-125 3725);
FORCEPROP 1 LAST BODY_TYPE PLUMBING
J 2
(-125 3675);
DISPLAY 1.234043 (-125 3675);
PAINT GREEN (-125 3675);
DISPLAY INVISIBLE (-125 3675);
FORCEPROP 1 LAST HDL_TAP TRUE
J 2
(-450 3600);
DISPLAY 1.234043 (-450 3600);
PAINT GREEN (-450 3600);
DISPLAY INVISIBLE (-450 3600);
FORCEPROP 1 LAST PATH I96
J 2
(-123 3725);
DISPLAY 0.872340 (-123 3725);
PAINT GREEN (-123 3725);
DISPLAY INVISIBLE (-123 3725);
FORCEADD TAP..6
R 2
(-125 3575);
FORCEPROP 3 LASTPIN (-175 3575) SIG_NAME M_L_DQ<43>
J 0
(-165 3585);
DISPLAY 0.659574 (-165 3585);
PAINT MONO (-165 3585);
DISPLAY INVISIBLE (-165 3585);
FORCEPROP 1 LASTPIN (-175 3575) BN 43
J 2
(-125 3585);
DISPLAY 0.617021 (-125 3585);
PAINT PINK (-125 3585);
FORCEPROP 2 LAST CDS_LIB mstr_standard
J 2
(-125 3575);
DISPLAY 0.787234 (-125 3575);
PAINT MONO (-125 3575);
DISPLAY INVISIBLE (-125 3575);
FORCEPROP 1 LAST BODY_TYPE PLUMBING
J 2
(-125 3525);
DISPLAY 1.234043 (-125 3525);
PAINT GREEN (-125 3525);
DISPLAY INVISIBLE (-125 3525);
FORCEPROP 1 LAST HDL_TAP TRUE
J 2
(-450 3450);
DISPLAY 1.234043 (-450 3450);
PAINT GREEN (-450 3450);
DISPLAY INVISIBLE (-450 3450);
FORCEPROP 1 LAST PATH I97
J 2
(-123 3575);
DISPLAY 0.872340 (-123 3575);
PAINT GREEN (-123 3575);
DISPLAY INVISIBLE (-123 3575);
FORCEADD TAP..6
R 2
(-125 3525);
FORCEPROP 3 LASTPIN (-175 3525) SIG_NAME M_L_DQ<42>
J 0
(-165 3535);
DISPLAY 0.659574 (-165 3535);
PAINT MONO (-165 3535);
DISPLAY INVISIBLE (-165 3535);
FORCEPROP 1 LASTPIN (-175 3525) BN 42
J 2
(-125 3535);
DISPLAY 0.617021 (-125 3535);
PAINT PINK (-125 3535);
FORCEPROP 2 LAST CDS_LIB mstr_standard
J 2
(-125 3525);
DISPLAY 0.787234 (-125 3525);
PAINT MONO (-125 3525);
DISPLAY INVISIBLE (-125 3525);
FORCEPROP 1 LAST BODY_TYPE PLUMBING
J 2
(-125 3475);
DISPLAY 1.234043 (-125 3475);
PAINT GREEN (-125 3475);
DISPLAY INVISIBLE (-125 3475);
FORCEPROP 1 LAST HDL_TAP TRUE
J 2
(-450 3400);
DISPLAY 1.234043 (-450 3400);
PAINT GREEN (-450 3400);
DISPLAY INVISIBLE (-450 3400);
FORCEPROP 1 LAST PATH I98
J 2
(-123 3525);
DISPLAY 0.872340 (-123 3525);
PAINT GREEN (-123 3525);
DISPLAY INVISIBLE (-123 3525);
FORCEADD PVPP_KLM..1
(675 2750);
FORCEPROP 3 LASTPIN (675 2700) SIG_NAME PVPP_KLM\g
J 0
(685 2710);
DISPLAY 0.659574 (685 2710);
PAINT MONO (685 2710);
DISPLAY INVISIBLE (685 2710);
FORCEPROP 1 LAST VOLTAGE 2.5V
J 0
(630 2707);
DISPLAY 0.340426 (630 2707);
PAINT SKYBLUE (630 2707);
DISPLAY INVISIBLE (630 2707);
FORCEPROP 0 LAST BOM_COST MEM
J 0
(675 2850);
PAINT ORANGE (675 2850);
DISPLAY INVISIBLE (675 2850);
FORCEPROP 2 LAST CDS_LIB mstr_symbols
J 0
(675 2750);
PAINT ORANGE (675 2750);
DISPLAY INVISIBLE (675 2750);
FORCEPROP 1 LAST BODY_TYPE PLUMBING
J 0
(630 2707);
DISPLAY 0.340426 (630 2707);
PAINT GREEN (630 2707);
DISPLAY INVISIBLE (630 2707);
FORCEPROP 1 LAST PATH I99
J 0
(725 2775);
DISPLAY 0.872340 (725 2775);
PAINT AQUA (725 2775);
DISPLAY INVISIBLE (725 2775);
FORCEPROP 2 LAST ROOM DDR4_CH_D
J 0
(675 2850);
PAINT ORANGE (675 2850);
DISPLAY INVISIBLE (675 2850);
FORCEPROP 1 LAST HDL_POWER PVPP_KLM
J 1
(675 2800);
DISPLAY 0.872340 (675 2800);
PAINT GREEN (675 2800);
DISPLAY INVISIBLE (675 2800);
FORCEADD BOM_NOTE..1
(-3375 4925);
FORCEPROP 0 LAST L1 UNSTUFF FOR SKU B
J 0
(-3525 4825);
DISPLAY 1.063830 (-3525 4825);
PAINT WHITE (-3525 4825);
FORCEPROP 2 LAST BOM_COST SB
J 0
(-3525 4900);
DISPLAY 1.361702 (-3525 4900);
PAINT ORANGE (-3525 4900);
DISPLAY INVISIBLE (-3525 4900);
FORCEPROP 2 LAST CDS_LIB mstr_symbols
J 0
(-3375 4925);
PAINT ORANGE (-3375 4925);
DISPLAY INVISIBLE (-3375 4925);
FORCEPROP 1 LAST COMMENT_BODY TRUE
J 0
(-3350 5025);
DISPLAY 1.319149 (-3350 5025);
PAINT ORANGE (-3350 5025);
DISPLAY INVISIBLE (-3350 5025);
FORCEPROP 2 LAST ROOM SB_HEADERS
J 0
(-3525 4900);
DISPLAY 1.361702 (-3525 4900);
PAINT ORANGE (-3525 4900);
DISPLAY INVISIBLE (-3525 4900);
FORCEADD INTEL_CORP_BPAGE..1
(4250 200);
FORCEPROP 1 LAST CDS_CON_LAST_MODIFIED Tue Dec 01 11:51:45 2015
J 0
(2825 525);
PAINT ORANGE (2825 525);
DISPLAY INVISIBLE (2825 525);
FORCEPROP 1 LAST CUSTOM_TXT_CDS <CURRENT_DESIGN_SHEET> OF <TOTAL_DESIGN_SHEETS>
J 0
(3750 225);
PAINT GREEN (3750 225);
FORCEPROP 1 LAST CUSTOM_TXT_CDS <CON_LAST_MODIFIED>
J 0
(2325 550);
PAINT GREEN (2325 550);
FORCEPROP 2 LAST CUSTOM_TXT_CDS <XR_PAGE_TITLE>
J 0
(-3640 5450);
DISPLAY 0.638298 (-3640 5450);
PAINT PINK (-3640 5450);
DISPLAY INVISIBLE (-3640 5450);
FORCEPROP 1 LAST SCH_ADDRESS3 Santa Clara, CA 95052-8119
J 0
(275 225);
DISPLAY 0.617021 (275 225);
PAINT GREEN (275 225);
FORCEPROP 1 LAST SCH_ADDRESS2 P.O. BOX 58119
J 0
(275 275);
DISPLAY 0.617021 (275 275);
PAINT GREEN (275 275);
FORCEPROP 1 LAST SCH_ADDRESS1 2200 Mission College Blvd.
J 0
(275 325);
DISPLAY 0.617021 (275 325);
PAINT GREEN (275 325);
FORCEPROP 1 LAST SCH_TITLE CPU1 DDR4 CH L DIMM1
J 0
(-3700 250);
DISPLAY 1.212766 (-3700 250);
PAINT ORANGE (-3700 250);
FORCEPROP 1 LAST SCH_NUMBER H4694802
J 0
(2950 350);
DISPLAY 1.212766 (2950 350);
PAINT YELLOW (2950 350);
FORCEPROP 1 LAST SCH_DEPT BESD
J 1
(-200 300);
DISPLAY 1.212766 (-200 300);
PAINT YELLOW (-200 300);
FORCEPROP 1 LAST SCH_REV 2.420
J 0
(4000 350);
DISPLAY 0.978723 (4000 350);
PAINT YELLOW (4000 350);
FORCEPROP 2 LAST PAGE_BORDER TRUE
J 0
(-3640 5450);
DISPLAY 0.638298 (-3640 5450);
PAINT PINK (-3640 5450);
DISPLAY INVISIBLE (-3640 5450);
FORCEPROP 2 LAST CDS_LIB mstr_symbols
J 0
(4250 200);
PAINT MONO (4250 200);
DISPLAY INVISIBLE (4250 200);
FORCEPROP 1 LAST COMMENT_BODY TRUE
J 0
(4262 212);
DISPLAY 0.468085 (4262 212);
PAINT GREEN (4262 212);
DISPLAY INVISIBLE (4262 212);
FORCEPROP 2 LAST CDS_XR_PAGE_TITLE CR-86 : @BASEBOARD_FAB2_LIB.BASEBOARD_FAB2(SCH_1):PAGE86
J 0
(-3640 5450);
DISPLAY 0.638298 (-3640 5450);
PAINT PINK (-3640 5450);
DISPLAY INVISIBLE (-3640 5450);
WIRE 17 -1 (2575 4800)(2575 4825);
WIRE 17 -1 (2575 4700)(2575 4800);
WIRE 17 -1 (3175 4825)(2575 4825);
FORCEPROP 2 LAST SIG_NAME M_L_DQS_DN<17:0>
J 0
(2625 4835);
DISPLAY 0.617021 (2625 4835);
PAINT ORANGE (2625 4835);
WIRE 17 -1 (2575 4600)(2575 4700);
WIRE 17 -1 (2375 4850)(2375 4875);
WIRE 17 -1 (2375 4750)(2375 4850);
WIRE 17 -1 (3175 4875)(2375 4875);
FORCEPROP 2 LAST SIG_NAME M_L_DQS_DP<17:0>
J 0
(2625 4885);
DISPLAY 0.617021 (2625 4885);
PAINT ORANGE (2625 4885);
WIRE 17 -1 (2375 4650)(2375 4750);
WIRE 17 -1 (2375 4550)(2375 4650);
WIRE 17 -1 (2375 4450)(2375 4550);
WIRE 17 -1 (2375 4350)(2375 4450);
WIRE 17 -1 (2575 4500)(2575 4600);
WIRE 17 -1 (2575 4400)(2575 4500);
WIRE 17 -1 (2575 4300)(2575 4400);
WIRE 17 -1 (2575 4200)(2575 4300);
WIRE 17 -1 (2575 4100)(2575 4200);
WIRE 17 -1 (2575 4000)(2575 4100);
WIRE 17 -1 (2575 3900)(2575 4000);
WIRE 17 -1 (2575 3800)(2575 3900);
WIRE 17 -1 (2575 3700)(2575 3800);
WIRE 17 -1 (2575 3600)(2575 3700);
WIRE 17 -1 (2575 3500)(2575 3600);
WIRE 17 -1 (2375 4250)(2375 4350);
WIRE 17 -1 (2375 4150)(2375 4250);
WIRE 17 -1 (2375 4050)(2375 4150);
WIRE 17 -1 (2375 3950)(2375 4050);
WIRE 17 -1 (2375 3850)(2375 3950);
WIRE 17 -1 (2375 3750)(2375 3850);
WIRE 17 -1 (2375 3650)(2375 3750);
WIRE 17 -1 (2375 3550)(2375 3650);
WIRE 17 -1 (2375 3450)(2375 3550);
WIRE 17 -1 (2575 3400)(2575 3500);
WIRE 17 -1 (2575 3300)(2575 3400);
WIRE 17 -1 (2575 3200)(2575 3300);
WIRE 17 -1 (2575 3100)(2575 3200);
WIRE 17 -1 (2375 3350)(2375 3450);
WIRE 17 -1 (2375 3250)(2375 3350);
WIRE 17 -1 (2375 3150)(2375 3250);
WIRE 17 -1 (-75 4150)(-75 4200);
WIRE 17 -1 (-75 4100)(-75 4150);
WIRE 17 -1 (-75 4200)(-75 4250);
WIRE 17 -1 (-75 4250)(-75 4300);
WIRE 17 -1 (-75 4050)(-75 4100);
WIRE 17 -1 (-75 4000)(-75 4050);
WIRE 17 -1 (-75 4300)(-75 4350);
WIRE 17 -1 (-75 4350)(-75 4400);
WIRE 17 -1 (-75 3950)(-75 4000);
WIRE 17 -1 (-75 3900)(-75 3950);
WIRE 17 -1 (-75 4400)(-75 4450);
WIRE 17 -1 (-75 4450)(-75 4500);
WIRE 17 -1 (-75 3850)(-75 3900);
WIRE 17 -1 (-75 3800)(-75 3850);
WIRE 17 -1 (-75 4500)(-75 4550);
WIRE 17 -1 (-75 4550)(-75 4600);
WIRE 17 -1 (-75 3750)(-75 3800);
WIRE 17 -1 (-75 3700)(-75 3750);
WIRE 17 -1 (-75 4625)(-75 4600);
WIRE 17 -1 (400 4625)(-75 4625);
FORCEPROP 2 LAST SIG_NAME M_L_DQ<63:0>
J 0
(-35 4635);
DISPLAY 0.617021 (-35 4635);
PAINT ORANGE (-35 4635);
WIRE 17 -1 (-1675 4500)(-1675 4550);
WIRE 17 -1 (-1675 4450)(-1675 4500);
WIRE 17 -1 (-1675 4550)(-1675 4600);
WIRE 17 -1 (-1675 4600)(-1675 4625);
WIRE 17 -1 (-1675 4400)(-1675 4450);
WIRE 17 -1 (-1675 4350)(-1675 4400);
WIRE 17 -1 (-2175 4625)(-1675 4625);
FORCEPROP 2 LAST SIG_NAME M_L_MA<17:0>
J 0
(-2150 4635);
DISPLAY 0.617021 (-2150 4635);
PAINT ORANGE (-2150 4635);
WIRE 17 -1 (-1675 4300)(-1675 4350);
WIRE 17 -1 (-1675 4250)(-1675 4300);
WIRE 17 -1 (-1675 4200)(-1675 4250);
WIRE 17 -1 (-1675 4150)(-1675 4200);
WIRE 17 -1 (-1675 4100)(-1675 4150);
WIRE 17 -1 (-1675 4050)(-1675 4100);
WIRE 17 -1 (-1675 4000)(-1675 4050);
WIRE 17 -1 (-1675 3950)(-1675 4000);
WIRE 17 -1 (-1675 3900)(-1675 3950);
WIRE 17 -1 (-1675 3850)(-1675 3900);
WIRE 17 -1 (-1675 3800)(-1675 3850);
WIRE 17 -1 (-1675 3750)(-1675 3800);
WIRE 17 -1 (-75 3650)(-75 3700);
WIRE 17 -1 (-75 3600)(-75 3650);
WIRE 17 -1 (-75 3550)(-75 3600);
WIRE 17 -1 (-75 3500)(-75 3550);
WIRE 17 -1 (-75 3450)(-75 3500);
WIRE 17 -1 (-75 3400)(-75 3450);
WIRE 17 -1 (-75 3350)(-75 3400);
WIRE 17 -1 (-75 3300)(-75 3350);
WIRE 17 -1 (-75 3250)(-75 3300);
WIRE 17 -1 (-75 3200)(-75 3250);
WIRE 17 -1 (-75 3150)(-75 3200);
WIRE 17 -1 (-75 3100)(-75 3150);
WIRE 17 -1 (-75 3050)(-75 3100);
WIRE 17 -1 (-75 3000)(-75 3050);
WIRE 17 -1 (-75 2950)(-75 3000);
WIRE 17 -1 (-75 2900)(-75 2950);
WIRE 17 -1 (-75 2850)(-75 2900);
WIRE 17 -1 (-75 2800)(-75 2850);
WIRE 17 -1 (-75 2750)(-75 2800);
WIRE 17 -1 (-75 2700)(-75 2750);
WIRE 17 -1 (-75 2650)(-75 2700);
WIRE 17 -1 (-75 2600)(-75 2650);
WIRE 17 -1 (-75 2550)(-75 2600);
WIRE 17 -1 (-75 2500)(-75 2550);
WIRE 17 -1 (-75 2450)(-75 2500);
WIRE 17 -1 (-75 2400)(-75 2450);
WIRE 17 -1 (-75 2350)(-75 2400);
WIRE 17 -1 (-75 2300)(-75 2350);
WIRE 17 -1 (-75 2250)(-75 2300);
WIRE 17 -1 (-75 2200)(-75 2250);
WIRE 17 -1 (-75 2150)(-75 2200);
WIRE 17 -1 (-75 2100)(-75 2150);
WIRE 17 -1 (-75 2050)(-75 2100);
WIRE 17 -1 (-75 2000)(-75 2050);
WIRE 17 -1 (-75 1950)(-75 2000);
WIRE 17 -1 (-75 1900)(-75 1950);
WIRE 17 -1 (-75 1850)(-75 1900);
WIRE 17 -1 (-75 1800)(-75 1850);
WIRE 17 -1 (-75 1750)(-75 1800);
WIRE 17 -1 (-75 1700)(-75 1750);
WIRE 17 -1 (-75 1650)(-75 1700);
WIRE 17 -1 (-75 1600)(-75 1650);
WIRE 17 -1 (-75 1550)(-75 1600);
WIRE 17 -1 (-75 1500)(-75 1550);
WIRE 17 -1 (-75 1450)(-75 1500);
WIRE 17 -1 (-1875 3350)(-1875 3250);
WIRE 17 -1 (-1875 3375)(-1875 3350);
WIRE 17 -1 (-1875 3375)(-2175 3375);
FORCEPROP 2 LAST SIG_NAME M_L_CLK_DN<3:0>
J 0
(-2175 3385);
DISPLAY 0.617021 (-2175 3385);
PAINT ORANGE (-2175 3385);
WIRE 17 -1 (-1675 3400)(-1675 3425);
WIRE 17 -1 (-1675 3300)(-1675 3400);
WIRE 17 -1 (-1675 3425)(-2175 3425);
FORCEPROP 2 LAST SIG_NAME M_L_CLK_DP<3:0>
J 0
(-2175 3435);
DISPLAY 0.617021 (-2175 3435);
PAINT ORANGE (-2175 3435);
WIRE 17 -1 (-1675 3500)(-1675 3550);
WIRE 17 -1 (-1675 3550)(-2175 3550);
FORCEPROP 2 LAST SIG_NAME M_L_BG<1:0>
J 0
(-2150 3560);
DISPLAY 0.617021 (-2150 3560);
PAINT ORANGE (-2150 3560);
WIRE 17 -1 (-1675 3600)(-1675 3650);
WIRE 17 -1 (-1675 3675)(-1675 3650);
WIRE 17 -1 (-1675 3675)(-2175 3675);
FORCEPROP 2 LAST SIG_NAME M_L_BA<1:0>
J 0
(-2150 3685);
DISPLAY 0.617021 (-2150 3685);
PAINT ORANGE (-2150 3685);
WIRE 17 -1 (-1675 3100)(-1675 3125);
WIRE 17 -1 (-1675 3050)(-1675 3100);
WIRE 17 -1 (-1675 3125)(-2175 3125);
FORCEPROP 2 LAST SIG_NAME M_L_CS_N<7:0>
J 0
(-2150 3135);
DISPLAY 0.617021 (-2150 3135);
PAINT ORANGE (-2150 3135);
WIRE 17 -1 (-1675 2950)(-1675 3000);
WIRE 17 -1 (-1675 3000)(-1675 3050);
WIRE 17 -1 (-1675 2800)(-1675 2850);
WIRE 17 -1 (-1675 2850)(-1675 2875);
WIRE 17 -1 (-1675 2875)(-2175 2875);
FORCEPROP 2 LAST SIG_NAME M_L_CKE<3:0>
J 0
(-2150 2885);
DISPLAY 0.617021 (-2150 2885);
PAINT ORANGE (-2150 2885);
WIRE 17 -1 (-1675 2700)(-1675 2725);
WIRE 17 -1 (-1675 2650)(-1675 2700);
WIRE 17 -1 (-1675 2725)(-2175 2725);
FORCEPROP 2 LAST SIG_NAME M_L_ODT<3:0>
J 0
(-2150 2735);
DISPLAY 0.617021 (-2150 2735);
PAINT ORANGE (-2150 2735);
WIRE 17 -1 (-1675 2550)(-1675 2575);
WIRE 17 -1 (-1675 2500)(-1675 2550);
WIRE 17 -1 (-1675 2575)(-2175 2575);
FORCEPROP 2 LAST SIG_NAME M_L_ECC<7:0>
J 0
(-2150 2585);
DISPLAY 0.617021 (-2150 2585);
PAINT ORANGE (-2150 2585);
WIRE 17 -1 (-1675 2200)(-1675 2250);
WIRE 17 -1 (-1675 2250)(-1675 2300);
WIRE 17 -1 (-1675 2300)(-1675 2350);
WIRE 17 -1 (-1675 2350)(-1675 2400);
WIRE 17 -1 (-1675 2400)(-1675 2450);
WIRE 17 -1 (-1675 2450)(-1675 2500);
WIRE 16 -1 (-3525 1725)(-1375 1725);
WIRE 16 -1 (-3525 1725)(-3525 1575);
WIRE 16 -1 (2725 3225)(2925 3225);
WIRE 16 -1 (2725 3175)(2725 3225);
WIRE 16 -1 (2725 3175)(2925 3175);
WIRE 16 -1 (2725 3125)(2725 3175);
WIRE 16 -1 (2725 3125)(2925 3125);
WIRE 16 -1 (2725 3075)(2725 3125);
WIRE 16 -1 (2725 3075)(2925 3075);
WIRE 16 -1 (2725 3025)(2725 3075);
WIRE 16 -1 (2725 3025)(2925 3025);
WIRE 16 -1 (2725 2975)(2725 3025);
WIRE 16 -1 (2725 2975)(2925 2975);
WIRE 16 -1 (2725 2925)(2725 2975);
WIRE 16 -1 (2725 2925)(2925 2925);
WIRE 16 -1 (2725 2875)(2725 2925);
WIRE 16 -1 (2725 2875)(2925 2875);
WIRE 16 -1 (2725 2825)(2725 2875);
WIRE 16 -1 (2725 2825)(2925 2825);
WIRE 16 -1 (2725 2775)(2725 2825);
WIRE 16 -1 (2725 2775)(2925 2775);
WIRE 16 -1 (2725 2725)(2725 2775);
WIRE 16 -1 (2725 2725)(2925 2725);
WIRE 16 -1 (2725 2675)(2725 2725);
WIRE 16 -1 (2725 2675)(2925 2675);
WIRE 16 -1 (2725 2625)(2725 2675);
WIRE 16 -1 (2725 2625)(2925 2625);
WIRE 16 -1 (2725 2575)(2725 2625);
WIRE 16 -1 (2725 2575)(2925 2575);
WIRE 16 -1 (2725 2525)(2725 2575);
WIRE 16 -1 (2725 2525)(2925 2525);
WIRE 16 -1 (2725 2475)(2725 2525);
WIRE 16 -1 (2725 2475)(2925 2475);
WIRE 16 -1 (2725 2425)(2725 2475);
WIRE 16 -1 (2725 2425)(2925 2425);
WIRE 16 -1 (2725 2375)(2725 2425);
WIRE 16 -1 (2725 2375)(2925 2375);
WIRE 16 -1 (2725 2325)(2725 2375);
WIRE 16 -1 (2725 2325)(2925 2325);
WIRE 16 -1 (2725 2275)(2725 2325);
WIRE 16 -1 (2725 2275)(2925 2275);
WIRE 16 -1 (2725 2225)(2725 2275);
WIRE 16 -1 (2725 2225)(2925 2225);
WIRE 16 -1 (2725 2175)(2725 2225);
WIRE 16 -1 (2725 2175)(2925 2175);
WIRE 16 -1 (2725 2125)(2725 2175);
WIRE 16 -1 (2725 2125)(2925 2125);
WIRE 16 -1 (2725 2075)(2725 2125);
WIRE 16 -1 (2725 2075)(2925 2075);
WIRE 16 -1 (2725 2025)(2725 2075);
WIRE 16 -1 (2725 2025)(2925 2025);
WIRE 16 -1 (2725 1975)(2725 2025);
WIRE 16 -1 (2725 1975)(2925 1975);
WIRE 16 -1 (2725 1925)(2725 1975);
WIRE 16 -1 (2725 1925)(2925 1925);
WIRE 16 -1 (2725 1875)(2725 1925);
WIRE 16 -1 (2725 1875)(2925 1875);
WIRE 16 -1 (2725 1825)(2725 1875);
WIRE 16 -1 (2725 1825)(2925 1825);
WIRE 16 -1 (2725 1775)(2725 1825);
WIRE 16 -1 (2725 1775)(2925 1775);
WIRE 16 -1 (2725 1725)(2725 1775);
WIRE 16 -1 (2725 1725)(2925 1725);
WIRE 16 -1 (2725 1675)(2725 1725);
WIRE 16 -1 (2725 1675)(2925 1675);
WIRE 16 -1 (2725 1625)(2725 1675);
WIRE 16 -1 (2725 1625)(2925 1625);
WIRE 16 -1 (2725 1575)(2725 1625);
WIRE 16 -1 (2725 1575)(2925 1575);
WIRE 16 -1 (2725 1525)(2725 1575);
WIRE 16 -1 (2725 1525)(2925 1525);
WIRE 16 -1 (2725 1475)(2725 1525);
WIRE 16 -1 (2725 1475)(2925 1475);
WIRE 16 -1 (2725 1425)(2725 1475);
WIRE 16 -1 (2725 1425)(2925 1425);
WIRE 16 -1 (2725 1375)(2725 1425);
WIRE 16 -1 (2725 1375)(2925 1375);
WIRE 16 -1 (2725 1325)(2725 1375);
WIRE 16 -1 (2725 1325)(2925 1325);
WIRE 16 -1 (2725 1275)(2725 1325);
WIRE 16 -1 (2725 1275)(2925 1275);
WIRE 16 -1 (2725 1225)(2725 1275);
WIRE 16 -1 (2725 1225)(2925 1225);
WIRE 16 -1 (2725 1175)(2725 1225);
WIRE 16 -1 (2725 1175)(2925 1175);
WIRE 16 -1 (2725 1125)(2725 1175);
WIRE 16 -1 (2725 1125)(2925 1125);
WIRE 16 -1 (2725 1075)(2725 1125);
WIRE 16 -1 (2725 1075)(2925 1075);
WIRE 16 -1 (2725 1025)(2725 1075);
WIRE 16 -1 (2725 1025)(2925 1025);
WIRE 16 -1 (2725 975)(2725 1025);
WIRE 16 -1 (2725 975)(2925 975);
WIRE 16 -1 (2725 925)(2725 975);
WIRE 16 -1 (2725 925)(2925 925);
WIRE 16 -1 (2725 825)(2725 925);
WIRE 16 -1 (4125 3175)(4125 3225);
WIRE 16 -1 (4125 3125)(4125 3175);
WIRE 16 -1 (4125 3175)(3925 3175);
WIRE 16 -1 (4125 3225)(3925 3225);
WIRE 16 -1 (4125 3075)(4125 3125);
WIRE 16 -1 (4125 3125)(3925 3125);
WIRE 16 -1 (4125 3025)(4125 3075);
WIRE 16 -1 (4125 3075)(3925 3075);
WIRE 16 -1 (4125 2975)(4125 3025);
WIRE 16 -1 (4125 3025)(3925 3025);
WIRE 16 -1 (4125 2925)(4125 2975);
WIRE 16 -1 (4125 2975)(3925 2975);
WIRE 16 -1 (4125 2875)(4125 2925);
WIRE 16 -1 (4125 2925)(3925 2925);
WIRE 16 -1 (4125 2825)(4125 2875);
WIRE 16 -1 (4125 2875)(3925 2875);
WIRE 16 -1 (4125 2775)(4125 2825);
WIRE 16 -1 (4125 2825)(3925 2825);
WIRE 16 -1 (4125 2725)(4125 2775);
WIRE 16 -1 (4125 2775)(3925 2775);
WIRE 16 -1 (4125 2675)(4125 2725);
WIRE 16 -1 (4125 2725)(3925 2725);
WIRE 16 -1 (4125 2625)(4125 2675);
WIRE 16 -1 (4125 2675)(3925 2675);
WIRE 16 -1 (4125 2575)(4125 2625);
WIRE 16 -1 (4125 2625)(3925 2625);
WIRE 16 -1 (4125 2525)(4125 2575);
WIRE 16 -1 (4125 2575)(3925 2575);
WIRE 16 -1 (4125 2475)(4125 2525);
WIRE 16 -1 (4125 2525)(3925 2525);
WIRE 16 -1 (4125 2425)(4125 2475);
WIRE 16 -1 (4125 2475)(3925 2475);
WIRE 16 -1 (4125 2375)(4125 2425);
WIRE 16 -1 (4125 2425)(3925 2425);
WIRE 16 -1 (4125 2325)(4125 2375);
WIRE 16 -1 (4125 2375)(3925 2375);
WIRE 16 -1 (4125 2275)(4125 2325);
WIRE 16 -1 (4125 2325)(3925 2325);
WIRE 16 -1 (4125 2225)(4125 2275);
WIRE 16 -1 (4125 2275)(3925 2275);
WIRE 16 -1 (4125 2175)(4125 2225);
WIRE 16 -1 (4125 2225)(3925 2225);
WIRE 16 -1 (4125 2125)(4125 2175);
WIRE 16 -1 (4125 2175)(3925 2175);
WIRE 16 -1 (4125 2075)(4125 2125);
WIRE 16 -1 (4125 2125)(3925 2125);
WIRE 16 -1 (4125 2025)(4125 2075);
WIRE 16 -1 (4125 2075)(3925 2075);
WIRE 16 -1 (4125 1975)(4125 2025);
WIRE 16 -1 (4125 2025)(3925 2025);
WIRE 16 -1 (4125 1925)(4125 1975);
WIRE 16 -1 (4125 1975)(3925 1975);
WIRE 16 -1 (4125 1875)(4125 1925);
WIRE 16 -1 (4125 1925)(3925 1925);
WIRE 16 -1 (4125 1825)(4125 1875);
WIRE 16 -1 (4125 1875)(3925 1875);
WIRE 16 -1 (4125 1775)(4125 1825);
WIRE 16 -1 (4125 1825)(3925 1825);
WIRE 16 -1 (4125 1725)(4125 1775);
WIRE 16 -1 (4125 1775)(3925 1775);
WIRE 16 -1 (4125 1675)(4125 1725);
WIRE 16 -1 (4125 1725)(3925 1725);
WIRE 16 -1 (4125 1625)(4125 1675);
WIRE 16 -1 (4125 1675)(3925 1675);
WIRE 16 -1 (4125 1575)(4125 1625);
WIRE 16 -1 (4125 1625)(3925 1625);
WIRE 16 -1 (4125 1525)(4125 1575);
WIRE 16 -1 (4125 1575)(3925 1575);
WIRE 16 -1 (4125 1475)(4125 1525);
WIRE 16 -1 (4125 1525)(3925 1525);
WIRE 16 -1 (4125 1425)(4125 1475);
WIRE 16 -1 (4125 1475)(3925 1475);
WIRE 16 -1 (4125 1375)(4125 1425);
WIRE 16 -1 (4125 1425)(3925 1425);
WIRE 16 -1 (4125 1325)(4125 1375);
WIRE 16 -1 (4125 1375)(3925 1375);
WIRE 16 -1 (4125 1275)(4125 1325);
WIRE 16 -1 (4125 1325)(3925 1325);
WIRE 16 -1 (4125 1225)(4125 1275);
WIRE 16 -1 (4125 1275)(3925 1275);
WIRE 16 -1 (4125 1175)(4125 1225);
WIRE 16 -1 (4125 1225)(3925 1225);
WIRE 16 -1 (4125 1125)(4125 1175);
WIRE 16 -1 (4125 1175)(3925 1175);
WIRE 16 -1 (4125 1075)(4125 1125);
WIRE 16 -1 (4125 1125)(3925 1125);
WIRE 16 -1 (4125 1025)(4125 1075);
WIRE 16 -1 (4125 1075)(3925 1075);
WIRE 16 -1 (4125 975)(4125 1025);
WIRE 16 -1 (4125 1025)(3925 1025);
WIRE 16 -1 (4125 925)(4125 975);
WIRE 16 -1 (4125 975)(3925 975);
WIRE 16 -1 (4125 825)(4125 925);
WIRE 16 -1 (4125 925)(3925 925);
WIRE 16 -1 (1875 2525)(2000 2525);
WIRE 16 -1 (2000 2525)(2000 2575);
WIRE 16 -1 (1875 2575)(2000 2575);
WIRE 16 -1 (2000 2575)(2000 2650);
WIRE 16 -1 (-3025 1125)(-3025 1025);
WIRE 16 -1 (-1375 1625)(-1475 1625);
WIRE 16 -1 (-1475 1625)(-1475 1675);
WIRE 16 -1 (-1475 1675)(-1375 1675);
WIRE 16 -1 (-1475 1675)(-1475 1775);
WIRE 16 -1 (-1475 1775)(-1375 1775);
WIRE 16 -1 (-3525 1775)(-1475 1775);
WIRE 16 -1 (-3525 1775)(-3525 1875);
WIRE 16 -1 (675 875)(875 875);
WIRE 16 -1 (675 875)(675 925);
WIRE 16 -1 (675 925)(875 925);
WIRE 16 -1 (675 925)(675 975);
WIRE 16 -1 (675 975)(675 1025);
WIRE 16 -1 (675 975)(875 975);
WIRE 16 -1 (675 1025)(875 1025);
WIRE 16 -1 (675 1025)(675 1075);
WIRE 16 -1 (675 1075)(875 1075);
WIRE 16 -1 (675 1075)(675 1125);
WIRE 16 -1 (675 1125)(875 1125);
WIRE 16 -1 (675 1125)(675 1175);
WIRE 16 -1 (675 1175)(875 1175);
WIRE 16 -1 (675 1175)(675 1225);
WIRE 16 -1 (675 1225)(875 1225);
WIRE 16 -1 (675 1225)(675 1275);
WIRE 16 -1 (675 1275)(875 1275);
WIRE 16 -1 (675 1275)(675 1325);
WIRE 16 -1 (675 1325)(875 1325);
WIRE 16 -1 (675 1325)(675 1375);
WIRE 16 -1 (675 1375)(875 1375);
WIRE 16 -1 (675 1375)(675 1425);
WIRE 16 -1 (675 1425)(875 1425);
WIRE 16 -1 (675 1425)(675 1475);
WIRE 16 -1 (675 1475)(875 1475);
WIRE 16 -1 (675 1475)(675 1525);
WIRE 16 -1 (675 1525)(675 1575);
WIRE 16 -1 (675 1525)(875 1525);
WIRE 16 -1 (675 1575)(875 1575);
WIRE 16 -1 (675 1575)(675 1625);
WIRE 16 -1 (675 1625)(875 1625);
WIRE 16 -1 (675 1625)(675 1675);
WIRE 16 -1 (675 1675)(875 1675);
WIRE 16 -1 (675 1675)(675 1725);
WIRE 16 -1 (675 1725)(875 1725);
WIRE 16 -1 (675 1725)(675 1775);
WIRE 16 -1 (675 1775)(875 1775);
WIRE 16 -1 (675 1775)(675 1825);
WIRE 16 -1 (675 1825)(875 1825);
WIRE 16 -1 (675 1825)(675 1875);
WIRE 16 -1 (675 1875)(875 1875);
WIRE 16 -1 (675 1875)(675 1925);
WIRE 16 -1 (675 1925)(875 1925);
WIRE 16 -1 (675 1925)(675 1975);
WIRE 16 -1 (675 1975)(875 1975);
WIRE 16 -1 (675 1975)(675 2025);
WIRE 16 -1 (675 2025)(675 2075);
WIRE 16 -1 (675 2025)(875 2025);
WIRE 16 -1 (675 2075)(875 2075);
WIRE 16 -1 (675 2075)(675 2125);
WIRE 16 -1 (675 2125)(875 2125);
WIRE 16 -1 (275 2125)(675 2125);
WIRE 16 -1 (275 2225)(275 2125);
WIRE 16 -1 (675 2225)(875 2225);
WIRE 16 -1 (675 2225)(675 2275);
WIRE 16 -1 (675 2275)(875 2275);
WIRE 16 -1 (525 2275)(675 2275);
WIRE 16 -1 (525 2375)(525 2275);
WIRE 16 -1 (675 2375)(875 2375);
WIRE 16 -1 (675 2425)(675 2375);
WIRE 16 -1 (675 2425)(875 2425);
WIRE 16 -1 (675 2475)(675 2425);
WIRE 16 -1 (675 2475)(875 2475);
WIRE 16 -1 (675 2475)(675 2525);
WIRE 16 -1 (675 2575)(675 2525);
WIRE 16 -1 (675 2525)(875 2525);
WIRE 16 -1 (675 2575)(875 2575);
WIRE 16 -1 (675 2700)(675 2575);
WIRE 16 -1 (-1375 1875)(-2375 1875);
FORCEPROP 2 LAST SIG_NAME M_L_ACT_N
J 0
(-2325 1885);
DISPLAY 0.617021 (-2325 1885);
PAINT ORANGE (-2325 1885);
WIRE 16 -1 (-1375 1425)(-3025 1425);
FORCEPROP 2 LAST SIG_NAME M_L_VREF
J 0
(-2125 1435);
DISPLAY 0.617021 (-2125 1435);
PAINT ORANGE (-2125 1435);
WIRE 16 -1 (-3025 1425)(-3025 1325);
WIRE 16 -1 (-3125 1425)(-3025 1425);
WIRE 16 -1 (-2225 1325)(-1375 1325);
FORCEPROP 2 LAST SIG_NAME TP_CH_L_DIMM0_RFU_2
J 0
(-2175 1335);
DISPLAY 0.617021 (-2175 1335);
PAINT ORANGE (-2175 1335);
FORCEPROP 2 LASTPROP $XRERR UNIQUE?
J 0
(-2465 1325);
DISPLAY 0.638298 (-2465 1325);
PAINT MONO (-2465 1325);
DISPLAY INVISIBLE (-2465 1325);
WIRE 16 -1 (-2225 1225)(-1375 1225);
FORCEPROP 2 LAST SIG_NAME TP_CH_L_DIMM0_RFU_0
J 0
(-2175 1235);
DISPLAY 0.617021 (-2175 1235);
PAINT ORANGE (-2175 1235);
FORCEPROP 2 LASTPROP $XRERR UNIQUE?
J 0
(-2465 1225);
DISPLAY 0.638298 (-2465 1225);
PAINT MONO (-2465 1225);
DISPLAY INVISIBLE (-2465 1225);
WIRE 16 -1 (-2225 1275)(-1375 1275);
FORCEPROP 2 LAST SIG_NAME TP_CH_L_DIMM0_RFU_1
J 0
(-2175 1285);
DISPLAY 0.617021 (-2175 1285);
PAINT ORANGE (-2175 1285);
FORCEPROP 2 LASTPROP $XRERR UNIQUE?
J 0
(-2465 1275);
DISPLAY 0.638298 (-2465 1275);
PAINT MONO (-2465 1275);
DISPLAY INVISIBLE (-2465 1275);
WIRE 16 -1 (-2175 1525)(-1375 1525);
FORCEPROP 2 LAST SIG_NAME SMB_DDR_KLM_VPP_SCL
J 0
(-2135 1535);
DISPLAY 0.617021 (-2135 1535);
PAINT ORANGE (-2135 1535);
WIRE 16 -1 (-1375 1575)(-2175 1575);
WIRE 16 -1 (-1375 1925)(-2400 1925);
FORCEPROP 2 LAST SIG_NAME M_L_ALERT_N
J 0
(-2350 1935);
DISPLAY 0.617021 (-2350 1935);
PAINT ORANGE (-2350 1935);
WIRE 16 -1 (-2225 1125)(-1375 1125);
FORCEPROP 2 LAST SIG_NAME FM_ADR_COMPLETE_KLM_N
J 0
(-2175 1135);
DISPLAY 0.617021 (-2175 1135);
PAINT ORANGE (-2175 1135);
WIRE 16 -1 (-175 1475)(-375 1475);
WIRE 16 -1 (-175 1425)(-375 1425);
WIRE 16 -1 (-175 1525)(-375 1525);
WIRE 16 -1 (-175 2025)(-375 2025);
WIRE 16 -1 (-175 1975)(-375 1975);
WIRE 16 -1 (-175 1925)(-375 1925);
WIRE 16 -1 (-175 1825)(-375 1825);
WIRE 16 -1 (-175 1725)(-375 1725);
WIRE 16 -1 (-175 1625)(-375 1625);
WIRE 16 -1 (-175 1675)(-375 1675);
WIRE 16 -1 (-175 1775)(-375 1775);
WIRE 16 -1 (-175 1875)(-375 1875);
WIRE 16 -1 (-175 1575)(-375 1575);
WIRE 16 -1 (-1825 1975)(-1825 2225);
WIRE 16 -1 (-1825 1975)(-1375 1975);
WIRE 16 -1 (-1825 2225)(-2550 2225);
FORCEPROP 2 LAST SIG_NAME FM_DIMM_EVENT_COD_N
J 0
(-2527 2243);
DISPLAY 0.617021 (-2527 2243);
PAINT ORANGE (-2527 2243);
WIRE 16 -1 (-1775 2025)(-1775 2475);
WIRE 16 -1 (-1375 2025)(-1775 2025);
WIRE 16 -1 (-1775 2475)(-2175 2475);
FORCEPROP 2 LAST SIG_NAME M_KLM_RST_N
J 0
(-2150 2485);
DISPLAY 0.617021 (-2150 2485);
PAINT ORANGE (-2150 2485);
WIRE 16 -1 (-1375 2075)(-1725 2075);
WIRE 16 -1 (-1725 2075)(-1725 2525);
WIRE 16 -1 (-1725 2525)(-2175 2525);
FORCEPROP 2 LAST SIG_NAME M_L_PAR
J 0
(-2150 2535);
DISPLAY 0.617021 (-2150 2535);
PAINT ORANGE (-2150 2535);
WIRE 16 -1 (-1375 3025)(-1575 3025);
WIRE 16 -1 (-1375 2975)(-1575 2975);
WIRE 16 -1 (-1375 2475)(-1575 2475);
WIRE 16 -1 (-1375 2425)(-1575 2425);
WIRE 16 -1 (-1375 2375)(-1575 2375);
WIRE 16 -1 (-1375 2325)(-1575 2325);
WIRE 16 -1 (-1375 2275)(-1575 2275);
WIRE 16 -1 (-1375 2225)(-1575 2225);
WIRE 16 -1 (-1375 2175)(-1575 2175);
WIRE 16 -1 (-1375 2825)(-1575 2825);
WIRE 16 -1 (-1375 2525)(-1575 2525);
WIRE 16 -1 (-1375 2625)(-1575 2625);
WIRE 16 -1 (-1375 2675)(-1575 2675);
WIRE 16 -1 (-1375 2775)(-1575 2775);
WIRE 16 -1 (-1375 2925)(-1575 2925);
WIRE 16 -1 (-1550 3125)(-1375 3125);
WIRE 16 -1 (-1550 3175)(-1550 3125);
WIRE 16 -1 (-1550 3175)(-2175 3175);
FORCEPROP 2 LAST SIG_NAME M_L_C<2>
J 0
(-2150 3185);
DISPLAY 0.617021 (-2150 3185);
PAINT ORANGE (-2150 3185);
WIRE 16 -1 (-1375 3625)(-1575 3625);
WIRE 16 -1 (-1375 3075)(-1575 3075);
WIRE 16 -1 (-1375 3725)(-1575 3725);
WIRE 16 -1 (-1375 3775)(-1575 3775);
WIRE 16 -1 (-1375 3875)(-1575 3875);
WIRE 16 -1 (-1375 3925)(-1575 3925);
WIRE 16 -1 (-1375 3975)(-1575 3975);
WIRE 16 -1 (-1375 4025)(-1575 4025);
WIRE 16 -1 (-1375 4075)(-1575 4075);
WIRE 16 -1 (-1375 3525)(-1575 3525);
WIRE 16 -1 (-1375 3575)(-1575 3575);
WIRE 16 -1 (-1375 3825)(-1575 3825);
WIRE 16 -1 (-1375 3475)(-1575 3475);
WIRE 16 -1 (-1375 3275)(-1575 3275);
WIRE 16 -1 (-1375 3375)(-1575 3375);
WIRE 16 -1 (-1375 3325)(-1775 3325);
WIRE 16 -1 (-1375 3225)(-1775 3225);
WIRE 16 -1 (-175 2525)(-375 2525);
WIRE 16 -1 (-175 2475)(-375 2475);
WIRE 16 -1 (-175 2425)(-375 2425);
WIRE 16 -1 (-175 2375)(-375 2375);
WIRE 16 -1 (-175 2325)(-375 2325);
WIRE 16 -1 (-175 2225)(-375 2225);
WIRE 16 -1 (-175 2125)(-375 2125);
WIRE 16 -1 (-175 2075)(-375 2075);
WIRE 16 -1 (-175 2175)(-375 2175);
WIRE 16 -1 (-175 2275)(-375 2275);
WIRE 16 -1 (-175 2875)(-375 2875);
WIRE 16 -1 (-175 2825)(-375 2825);
WIRE 16 -1 (-175 3025)(-375 3025);
WIRE 16 -1 (-175 2975)(-375 2975);
WIRE 16 -1 (-175 2925)(-375 2925);
WIRE 16 -1 (-175 2675)(-375 2675);
WIRE 16 -1 (-175 2625)(-375 2625);
WIRE 16 -1 (-175 2575)(-375 2575);
WIRE 16 -1 (-175 2775)(-375 2775);
WIRE 16 -1 (-175 2725)(-375 2725);
WIRE 16 -1 (-175 3575)(-375 3575);
WIRE 16 -1 (-175 3525)(-375 3525);
WIRE 16 -1 (-175 3475)(-375 3475);
WIRE 16 -1 (-175 3425)(-375 3425);
WIRE 16 -1 (-175 3375)(-375 3375);
WIRE 16 -1 (-175 3275)(-375 3275);
WIRE 16 -1 (-175 3125)(-375 3125);
WIRE 16 -1 (-175 3075)(-375 3075);
WIRE 16 -1 (-175 3175)(-375 3175);
WIRE 16 -1 (-175 3225)(-375 3225);
WIRE 16 -1 (-175 3325)(-375 3325);
WIRE 16 -1 (-175 3725)(-375 3725);
WIRE 16 -1 (-175 3675)(-375 3675);
WIRE 16 -1 (-175 3625)(-375 3625);
WIRE 16 -1 (-175 4075)(-375 4075);
WIRE 16 -1 (-175 4025)(-375 4025);
WIRE 16 -1 (-175 3975)(-375 3975);
WIRE 16 -1 (-175 3925)(-375 3925);
WIRE 16 -1 (-175 3875)(-375 3875);
WIRE 16 -1 (-175 3825)(-375 3825);
WIRE 16 -1 (-175 3775)(-375 3775);
WIRE 16 -1 (-1375 4325)(-1575 4325);
WIRE 16 -1 (-1375 4375)(-1575 4375);
WIRE 16 -1 (-1375 4575)(-1575 4575);
WIRE 16 -1 (-1375 4125)(-1575 4125);
WIRE 16 -1 (-1375 4175)(-1575 4175);
WIRE 16 -1 (-1375 4225)(-1575 4225);
WIRE 16 -1 (-1375 4275)(-1575 4275);
WIRE 16 -1 (-1375 4425)(-1575 4425);
WIRE 16 -1 (-1375 4475)(-1575 4475);
WIRE 16 -1 (-1375 4525)(-1575 4525);
WIRE 16 -1 (-175 4575)(-375 4575);
WIRE 16 -1 (-175 4525)(-375 4525);
WIRE 16 -1 (-175 4475)(-375 4475);
WIRE 16 -1 (-175 4425)(-375 4425);
WIRE 16 -1 (-175 4375)(-375 4375);
WIRE 16 -1 (-175 4225)(-375 4225);
WIRE 16 -1 (-175 4175)(-375 4175);
WIRE 16 -1 (-175 4275)(-375 4275);
WIRE 16 -1 (-175 4325)(-375 4325);
WIRE 16 -1 (-175 4125)(-375 4125);
WIRE 16 -1 (2275 3125)(2075 3125);
WIRE 16 -1 (2275 3225)(2075 3225);
WIRE 16 -1 (2275 3325)(2075 3325);
WIRE 16 -1 (2275 3425)(2075 3425);
WIRE 16 -1 (2275 3525)(2075 3525);
WIRE 16 -1 (2475 3075)(2075 3075);
WIRE 16 -1 (2475 3175)(2075 3175);
WIRE 16 -1 (2475 3275)(2075 3275);
WIRE 16 -1 (2475 3375)(2075 3375);
WIRE 16 -1 (2475 3475)(2075 3475);
WIRE 16 -1 (2475 3575)(2075 3575);
WIRE 16 -1 (2275 3625)(2075 3625);
WIRE 16 -1 (2275 3725)(2075 3725);
WIRE 16 -1 (2275 3825)(2075 3825);
WIRE 16 -1 (2275 3925)(2075 3925);
WIRE 16 -1 (2275 4025)(2075 4025);
WIRE 16 -1 (2475 4075)(2075 4075);
WIRE 16 -1 (2475 3675)(2075 3675);
WIRE 16 -1 (2475 3775)(2075 3775);
WIRE 16 -1 (2475 3875)(2075 3875);
WIRE 16 -1 (2475 3975)(2075 3975);
WIRE 16 -1 (2275 4125)(2075 4125);
WIRE 16 -1 (2275 4225)(2075 4225);
WIRE 16 -1 (2275 4325)(2075 4325);
WIRE 16 -1 (2275 4425)(2075 4425);
WIRE 16 -1 (2275 4525)(2075 4525);
WIRE 16 -1 (2475 4175)(2075 4175);
WIRE 16 -1 (2475 4275)(2075 4275);
WIRE 16 -1 (2475 4375)(2075 4375);
WIRE 16 -1 (2475 4475)(2075 4475);
WIRE 16 -1 (2475 4575)(2075 4575);
WIRE 16 -1 (2275 4625)(2075 4625);
WIRE 16 -1 (2275 4725)(2075 4725);
WIRE 16 -1 (2275 4825)(2075 4825);
WIRE 16 -1 (2475 4675)(2075 4675);
WIRE 16 -1 (2475 4775)(2075 4775);
DOT 1 (4125 3175);
DOT 1 (4125 3025);
DOT 1 (4125 3075);
DOT 1 (4125 3125);
DOT 1 (4125 2925);
DOT 1 (4125 2975);
DOT 1 (4125 2825);
DOT 1 (4125 2775);
DOT 1 (4125 2875);
DOT 1 (4125 2675);
DOT 1 (4125 2725);
DOT 1 (4125 2625);
DOT 1 (4125 2525);
DOT 1 (4125 2575);
DOT 1 (4125 2425);
DOT 1 (4125 2475);
DOT 1 (4125 2375);
DOT 1 (4125 2325);
DOT 1 (4125 2275);
DOT 1 (4125 2125);
DOT 1 (4125 2175);
DOT 1 (4125 2225);
DOT 1 (4125 2025);
DOT 1 (4125 2075);
DOT 1 (4125 1875);
DOT 1 (4125 1925);
DOT 1 (4125 1975);
DOT 1 (4125 1775);
DOT 1 (4125 1825);
DOT 1 (4125 1725);
DOT 1 (4125 1625);
DOT 1 (4125 1675);
DOT 1 (4125 1525);
DOT 1 (4125 1575);
DOT 1 (4125 1475);
DOT 1 (4125 1425);
DOT 1 (4125 1375);
DOT 1 (4125 1275);
DOT 1 (4125 1225);
DOT 1 (4125 1325);
DOT 1 (4125 1175);
DOT 1 (4125 1125);
DOT 1 (4125 975);
DOT 1 (4125 1025);
DOT 1 (4125 1075);
DOT 1 (4125 925);
DOT 1 (2725 3175);
DOT 1 (2725 3075);
DOT 1 (2725 3025);
DOT 1 (2725 3125);
DOT 1 (2725 2925);
DOT 1 (2725 2975);
DOT 1 (2725 2875);
DOT 1 (2725 2825);
DOT 1 (2725 2775);
DOT 1 (2725 2675);
DOT 1 (2725 2725);
DOT 1 (2725 2625);
DOT 1 (2725 2575);
DOT 1 (2725 2525);
DOT 1 (2725 2425);
DOT 1 (2725 2475);
DOT 1 (2725 2375);
DOT 1 (2725 2325);
DOT 1 (2725 2275);
DOT 1 (2725 2225);
DOT 1 (2725 2125);
DOT 1 (2725 2175);
DOT 1 (2725 2075);
DOT 1 (2725 2025);
DOT 1 (2725 1875);
DOT 1 (2725 1925);
DOT 1 (2725 1975);
DOT 1 (2725 1775);
DOT 1 (2725 1825);
DOT 1 (2000 2575);
DOT 1 (2725 1725);
DOT 1 (2725 1675);
DOT 1 (2725 1625);
DOT 1 (2725 1525);
DOT 1 (2725 1575);
DOT 1 (2725 1475);
DOT 1 (2725 1375);
DOT 1 (2725 1425);
DOT 1 (2725 1275);
DOT 1 (2725 1225);
DOT 1 (2725 1325);
DOT 1 (2725 1175);
DOT 1 (2725 1125);
DOT 1 (2725 975);
DOT 1 (2725 1025);
DOT 1 (2725 1075);
DOT 1 (2725 925);
DOT 1 (675 2575);
DOT 1 (675 2525);
DOT 1 (675 2425);
DOT 1 (675 2475);
DOT 1 (675 2275);
DOT 1 (675 2125);
DOT 1 (675 2075);
DOT 1 (675 2025);
DOT 1 (675 1875);
DOT 1 (675 1925);
DOT 1 (675 1775);
DOT 1 (675 1825);
DOT 1 (675 1725);
DOT 1 (675 1675);
DOT 1 (675 1625);
DOT 1 (675 1575);
DOT 1 (675 1525);
DOT 1 (675 1475);
DOT 1 (675 1375);
DOT 1 (675 1425);
DOT 1 (675 1225);
DOT 1 (675 1275);
DOT 1 (675 1325);
DOT 1 (675 1175);
DOT 1 (675 1125);
DOT 1 (675 1075);
DOT 1 (675 1025);
DOT 1 (675 975);
DOT 1 (675 925);
DOT 1 (-3025 1425);
DOT 1 (-1475 1775);
DOT 1 (-1475 1675);
DOT 1 (675 1975);
FORCENOTE
SMBUS ADDR: 0XA6
(-1325 834) 0;
DISPLAY LEFT (-1325 834);
DISPLAY 1.957447 (-1325 834);
PAINT PURPLE (-1325 834);
FORCENOTE
PLACE CAP NEAR DIMM CONNECTOR
(-3663 877) 0;
DISPLAY LEFT (-3663 877);
DISPLAY 1.595745 (-3663 877);
PAINT PURPLE (-3663 877);
QUIT
